FILE_TYPE = MACRO_DRAWING;
SET COLOR_WIRE YELLOW;
SET COLOR_PROP ORANGE;
SET COLOR_DOT WHITE;
SET COLOR_ARC YELLOW;
SET COLOR_BODY GREEN;
SET COLOR_NOTE PURPLE;
SET PROP_DISPLAY VALUE;
SET PAGE_NUMBER P33;
FORCEADD TAP..1
R 2
(-850 1175);
FORCEPROP 3 LASTPIN (-800 1175) SIG_NAME UPI_CPU1_CPU0_P0P1_DN<0>
J 0
(-790 1185);
DISPLAY 0.659574 (-790 1185);
PAINT MONO (-790 1185);
DISPLAY INVISIBLE (-790 1185);
FORCEPROP 1 LASTPIN (-800 1175) BN 0
J 2
(-788 1183);
DISPLAY 0.680851 (-788 1183);
PAINT GREEN (-788 1183);
FORCEPROP 2 LAST CDS_LIB standard
J 0
(-850 1175);
DISPLAY INVISIBLE (-850 1175);
FORCEPROP 1 LAST BODY_TYPE PLUMBING
J 2
(-850 1225);
DISPLAY 0.872340 (-850 1225);
PAINT GREEN (-850 1225);
DISPLAY INVISIBLE (-850 1225);
FORCEPROP 1 LAST HDL_TAP TRUE
J 2
(-1175 1050);
DISPLAY 0.872340 (-1175 1050);
DISPLAY INVISIBLE (-1175 1050);
FORCEPROP 1 LAST PATH I1
J 2
(-848 1175);
DISPLAY 0.872340 (-848 1175);
PAINT GREEN (-848 1175);
DISPLAY INVISIBLE (-848 1175);
FORCEADD TAP..1
R 2
(-850 1625);
FORCEPROP 3 LASTPIN (-800 1625) SIG_NAME UPI_CPU1_CPU0_P0P1_DN<9>
J 0
(-790 1635);
DISPLAY 0.659574 (-790 1635);
PAINT MONO (-790 1635);
DISPLAY INVISIBLE (-790 1635);
FORCEPROP 1 LASTPIN (-800 1625) BN 9
J 2
(-788 1633);
DISPLAY 0.680851 (-788 1633);
PAINT GREEN (-788 1633);
FORCEPROP 2 LAST CDS_LIB standard
J 0
(-850 1625);
DISPLAY INVISIBLE (-850 1625);
FORCEPROP 1 LAST BODY_TYPE PLUMBING
J 2
(-850 1675);
DISPLAY 0.872340 (-850 1675);
PAINT GREEN (-850 1675);
DISPLAY INVISIBLE (-850 1675);
FORCEPROP 1 LAST HDL_TAP TRUE
J 2
(-1175 1500);
DISPLAY 0.872340 (-1175 1500);
DISPLAY INVISIBLE (-1175 1500);
FORCEPROP 1 LAST PATH I10
J 2
(-848 1625);
DISPLAY 0.872340 (-848 1625);
PAINT GREEN (-848 1625);
DISPLAY INVISIBLE (-848 1625);
FORCEADD OFFPAGE..2
(4075 3725);
FORCEPROP 2 LAST $XR0 63 
J 0
(4264 3725);
DISPLAY 0.638298 (4264 3725);
PAINT MONO (4264 3725);
FORCEPROP 2 LAST CDS_LIB standard
J 0
(4075 3725);
PAINT MONO (4075 3725);
DISPLAY INVISIBLE (4075 3725);
FORCEPROP 1 LAST OFFPAGE TRUE
J 0
(4400 3600);
DISPLAY 1.170213 (4400 3600);
PAINT GREEN (4400 3600);
DISPLAY INVISIBLE (4400 3600);
FORCEPROP 1 LAST COMMENT_BODY TRUE
J 0
(4030 3630);
DISPLAY 1.170213 (4030 3630);
PAINT GREEN (4030 3630);
DISPLAY INVISIBLE (4030 3630);
FORCEPROP 2 LAST PATH I101
J 0
(4250 3800);
DISPLAY 1.021277 (4250 3800);
DISPLAY INVISIBLE (4250 3800);
FORCEADD SOCKET4677_AZIF0045P001C01CS..23
(1050 2375);
FORCEPROP 1 LAST PART_NUMBER DGA^7000023
J 0
(0 3825);
DISPLAY 0.723404 (0 3825);
PAINT GREEN (0 3825);
DISPLAY INVISIBLE (0 3825);
FORCEPROP 2 LAST VALUE SOCKET4677_AZIF0045-P001C01CS
J 0
(0 3950);
DISPLAY 1.021277 (0 3950);
FORCEPROP 1 LAST MATERIAL IO
J 0
(0 3750);
DISPLAY 0.723404 (0 3750);
PAINT GREEN (0 3750);
FORCEPROP 2 LAST PART_TYPE SMLF
J 0
(0 4000);
DISPLAY 1.021277 (0 4000);
FORCEPROP 1 LAST $LOCATION U2
J 0
(0 3900);
DISPLAY 0.723404 (0 3900);
PAINT GREEN (0 3900);
FORCEPROP 0 LASTPIN (-150 1175) $PN EH2
J 2
(-160 1185);
DISPLAY 0.680851 (-160 1185);
PAINT MONO (-160 1185);
FORCEPROP 0 LASTPIN (-150 1225) $PN EE3
J 2
(-160 1235);
DISPLAY 0.680851 (-160 1235);
PAINT MONO (-160 1235);
FORCEPROP 0 LASTPIN (-150 1275) $PN ED2
J 2
(-160 1285);
DISPLAY 0.680851 (-160 1285);
PAINT MONO (-160 1285);
FORCEPROP 0 LASTPIN (-150 1325) $PN EA1
J 2
(-160 1335);
DISPLAY 0.680851 (-160 1335);
PAINT MONO (-160 1335);
FORCEPROP 0 LASTPIN (-150 1375) $PN DY2
J 2
(-160 1385);
DISPLAY 0.680851 (-160 1385);
PAINT MONO (-160 1385);
FORCEPROP 0 LASTPIN (-150 1425) $PN DU1
J 2
(-160 1435);
DISPLAY 0.680851 (-160 1435);
PAINT MONO (-160 1435);
FORCEPROP 0 LASTPIN (-150 1475) $PN DT2
J 2
(-160 1485);
DISPLAY 0.680851 (-160 1485);
PAINT MONO (-160 1485);
FORCEPROP 0 LASTPIN (-150 1525) $PN DN1
J 2
(-160 1535);
DISPLAY 0.680851 (-160 1535);
PAINT MONO (-160 1535);
FORCEPROP 0 LASTPIN (-150 1575) $PN DL3
J 2
(-160 1585);
DISPLAY 0.680851 (-160 1585);
PAINT MONO (-160 1585);
FORCEPROP 0 LASTPIN (-150 1625) $PN DJ1
J 2
(-160 1635);
DISPLAY 0.680851 (-160 1635);
PAINT MONO (-160 1635);
FORCEPROP 0 LASTPIN (-150 1675) $PN DG3
J 2
(-160 1685);
DISPLAY 0.680851 (-160 1685);
PAINT MONO (-160 1685);
FORCEPROP 0 LASTPIN (-150 1725) $PN DE1
J 2
(-160 1735);
DISPLAY 0.680851 (-160 1735);
PAINT MONO (-160 1735);
FORCEPROP 0 LASTPIN (-150 1775) $PN DD2
J 2
(-160 1785);
DISPLAY 0.680851 (-160 1785);
PAINT MONO (-160 1785);
FORCEPROP 0 LASTPIN (-150 1825) $PN DB2
J 2
(-160 1835);
DISPLAY 0.680851 (-160 1835);
PAINT MONO (-160 1835);
FORCEPROP 0 LASTPIN (-150 1875) $PN CY2
J 2
(-160 1885);
DISPLAY 0.680851 (-160 1885);
PAINT MONO (-160 1885);
FORCEPROP 0 LASTPIN (-150 1925) $PN CV2
J 2
(-160 1935);
DISPLAY 0.680851 (-160 1935);
PAINT MONO (-160 1935);
FORCEPROP 0 LASTPIN (-150 1975) $PN CR3
J 2
(-160 1985);
DISPLAY 0.680851 (-160 1985);
PAINT MONO (-160 1985);
FORCEPROP 0 LASTPIN (-150 2025) $PN CN1
J 2
(-160 2035);
DISPLAY 0.680851 (-160 2035);
PAINT MONO (-160 2035);
FORCEPROP 0 LASTPIN (-150 2075) $PN CL3
J 2
(-160 2085);
DISPLAY 0.680851 (-160 2085);
PAINT MONO (-160 2085);
FORCEPROP 0 LASTPIN (-150 2125) $PN CJ1
J 2
(-160 2135);
DISPLAY 0.680851 (-160 2135);
PAINT MONO (-160 2135);
FORCEPROP 0 LASTPIN (-150 2175) $PN CH2
J 2
(-160 2185);
DISPLAY 0.680851 (-160 2185);
PAINT MONO (-160 2185);
FORCEPROP 0 LASTPIN (-150 2225) $PN CF2
J 2
(-160 2235);
DISPLAY 0.680851 (-160 2235);
PAINT MONO (-160 2235);
FORCEPROP 0 LASTPIN (-150 2275) $PN CD2
J 2
(-160 2285);
DISPLAY 0.680851 (-160 2285);
PAINT MONO (-160 2285);
FORCEPROP 0 LASTPIN (-150 2325) $PN CB2
J 2
(-160 2335);
DISPLAY 0.680851 (-160 2335);
PAINT MONO (-160 2335);
FORCEPROP 0 LASTPIN (-150 2425) $PN EJ3
J 2
(-160 2435);
DISPLAY 0.680851 (-160 2435);
PAINT MONO (-160 2435);
FORCEPROP 0 LASTPIN (-150 2475) $PN EG3
J 2
(-160 2485);
DISPLAY 0.680851 (-160 2485);
PAINT MONO (-160 2485);
FORCEPROP 0 LASTPIN (-150 2525) $PN EC3
J 2
(-160 2535);
DISPLAY 0.680851 (-160 2535);
PAINT MONO (-160 2535);
FORCEPROP 0 LASTPIN (-150 2575) $PN EB2
J 2
(-160 2585);
DISPLAY 0.680851 (-160 2585);
PAINT MONO (-160 2585);
FORCEPROP 0 LASTPIN (-150 2625) $PN DW3
J 2
(-160 2635);
DISPLAY 0.680851 (-160 2635);
PAINT MONO (-160 2635);
FORCEPROP 0 LASTPIN (-150 2675) $PN DV2
J 2
(-160 2685);
DISPLAY 0.680851 (-160 2685);
PAINT MONO (-160 2685);
FORCEPROP 0 LASTPIN (-150 2725) $PN DR3
J 2
(-160 2735);
DISPLAY 0.680851 (-160 2735);
PAINT MONO (-160 2735);
FORCEPROP 0 LASTPIN (-150 2775) $PN DP2
J 2
(-160 2785);
DISPLAY 0.680851 (-160 2785);
PAINT MONO (-160 2785);
FORCEPROP 0 LASTPIN (-150 2825) $PN DM2
J 2
(-160 2835);
DISPLAY 0.680851 (-160 2835);
PAINT MONO (-160 2835);
FORCEPROP 0 LASTPIN (-150 2875) $PN DK2
J 2
(-160 2885);
DISPLAY 0.680851 (-160 2885);
PAINT MONO (-160 2885);
FORCEPROP 0 LASTPIN (-150 2925) $PN DH2
J 2
(-160 2935);
DISPLAY 0.680851 (-160 2935);
PAINT MONO (-160 2935);
FORCEPROP 0 LASTPIN (-150 2975) $PN DF2
J 2
(-160 2985);
DISPLAY 0.680851 (-160 2985);
PAINT MONO (-160 2985);
FORCEPROP 0 LASTPIN (-150 3025) $PN DC3
J 2
(-160 3035);
DISPLAY 0.680851 (-160 3035);
PAINT MONO (-160 3035);
FORCEPROP 0 LASTPIN (-150 3075) $PN DA1
J 2
(-160 3085);
DISPLAY 0.680851 (-160 3085);
PAINT MONO (-160 3085);
FORCEPROP 0 LASTPIN (-150 3125) $PN CW3
J 2
(-160 3135);
DISPLAY 0.680851 (-160 3135);
PAINT MONO (-160 3135);
FORCEPROP 0 LASTPIN (-150 3175) $PN CU1
J 2
(-160 3185);
DISPLAY 0.680851 (-160 3185);
PAINT MONO (-160 3185);
FORCEPROP 0 LASTPIN (-150 3225) $PN CT2
J 2
(-160 3235);
DISPLAY 0.680851 (-160 3235);
PAINT MONO (-160 3235);
FORCEPROP 0 LASTPIN (-150 3275) $PN CP2
J 2
(-160 3285);
DISPLAY 0.680851 (-160 3285);
PAINT MONO (-160 3285);
FORCEPROP 0 LASTPIN (-150 3325) $PN CM2
J 2
(-160 3335);
DISPLAY 0.680851 (-160 3335);
PAINT MONO (-160 3335);
FORCEPROP 0 LASTPIN (-150 3375) $PN CK2
J 2
(-160 3385);
DISPLAY 0.680851 (-160 3385);
PAINT MONO (-160 3385);
FORCEPROP 0 LASTPIN (-150 3425) $PN CG3
J 2
(-160 3435);
DISPLAY 0.680851 (-160 3435);
PAINT MONO (-160 3435);
FORCEPROP 0 LASTPIN (-150 3475) $PN CE1
J 2
(-160 3485);
DISPLAY 0.680851 (-160 3485);
PAINT MONO (-160 3485);
FORCEPROP 0 LASTPIN (-150 3525) $PN CC3
J 2
(-160 3535);
DISPLAY 0.680851 (-160 3535);
PAINT MONO (-160 3535);
FORCEPROP 0 LASTPIN (-150 3575) $PN BY2
J 2
(-160 3585);
DISPLAY 0.680851 (-160 3585);
PAINT MONO (-160 3585);
FORCEPROP 0 LASTPIN (2250 1175) $PN EF6
J 0
(2260 1185);
DISPLAY 0.680851 (2260 1185);
PAINT MONO (2260 1185);
FORCEPROP 0 LASTPIN (2250 1225) $PN EC7
J 0
(2260 1235);
DISPLAY 0.680851 (2260 1235);
PAINT MONO (2260 1235);
FORCEPROP 0 LASTPIN (2250 1275) $PN EB6
J 0
(2260 1285);
DISPLAY 0.680851 (2260 1285);
PAINT MONO (2260 1285);
FORCEPROP 0 LASTPIN (2250 1325) $PN DY6
J 0
(2260 1335);
DISPLAY 0.680851 (2260 1335);
PAINT MONO (2260 1335);
FORCEPROP 0 LASTPIN (2250 1375) $PN DV6
J 0
(2260 1385);
DISPLAY 0.680851 (2260 1385);
PAINT MONO (2260 1385);
FORCEPROP 0 LASTPIN (2250 1425) $PN DT6
J 0
(2260 1435);
DISPLAY 0.680851 (2260 1435);
PAINT MONO (2260 1435);
FORCEPROP 0 LASTPIN (2250 1475) $PN DP6
J 0
(2260 1485);
DISPLAY 0.680851 (2260 1485);
PAINT MONO (2260 1485);
FORCEPROP 0 LASTPIN (2250 1525) $PN DL7
J 0
(2260 1535);
DISPLAY 0.680851 (2260 1535);
PAINT MONO (2260 1535);
FORCEPROP 0 LASTPIN (2250 1575) $PN DK6
J 0
(2260 1585);
DISPLAY 0.680851 (2260 1585);
PAINT MONO (2260 1585);
FORCEPROP 0 LASTPIN (2250 1625) $PN DH6
J 0
(2260 1635);
DISPLAY 0.680851 (2260 1635);
PAINT MONO (2260 1635);
FORCEPROP 0 LASTPIN (2250 1675) $PN DE5
J 0
(2260 1685);
DISPLAY 0.680851 (2260 1685);
PAINT MONO (2260 1685);
FORCEPROP 0 LASTPIN (2250 1725) $PN DD6
J 0
(2260 1735);
DISPLAY 0.680851 (2260 1735);
PAINT MONO (2260 1735);
FORCEPROP 0 LASTPIN (2250 1775) $PN DA5
J 0
(2260 1785);
DISPLAY 0.680851 (2260 1785);
PAINT MONO (2260 1785);
FORCEPROP 0 LASTPIN (2250 1825) $PN CY6
J 0
(2260 1835);
DISPLAY 0.680851 (2260 1835);
PAINT MONO (2260 1835);
FORCEPROP 0 LASTPIN (2250 1875) $PN CU5
J 0
(2260 1885);
DISPLAY 0.680851 (2260 1885);
PAINT MONO (2260 1885);
FORCEPROP 0 LASTPIN (2250 1925) $PN CT6
J 0
(2260 1935);
DISPLAY 0.680851 (2260 1935);
PAINT MONO (2260 1935);
FORCEPROP 0 LASTPIN (2250 1975) $PN CN5
J 0
(2260 1985);
DISPLAY 0.680851 (2260 1985);
PAINT MONO (2260 1985);
FORCEPROP 0 LASTPIN (2250 2025) $PN CM6
J 0
(2260 2035);
DISPLAY 0.680851 (2260 2035);
PAINT MONO (2260 2035);
FORCEPROP 0 LASTPIN (2250 2075) $PN CJ5
J 0
(2260 2085);
DISPLAY 0.680851 (2260 2085);
PAINT MONO (2260 2085);
FORCEPROP 0 LASTPIN (2250 2125) $PN CH6
J 0
(2260 2135);
DISPLAY 0.680851 (2260 2135);
PAINT MONO (2260 2135);
FORCEPROP 0 LASTPIN (2250 2175) $PN CE5
J 0
(2260 2185);
DISPLAY 0.680851 (2260 2185);
PAINT MONO (2260 2185);
FORCEPROP 0 LASTPIN (2250 2225) $PN CD6
J 0
(2260 2235);
DISPLAY 0.680851 (2260 2235);
PAINT MONO (2260 2235);
FORCEPROP 0 LASTPIN (2250 2275) $PN CA5
J 0
(2260 2285);
DISPLAY 0.680851 (2260 2285);
PAINT MONO (2260 2285);
FORCEPROP 0 LASTPIN (2250 2325) $PN BY6
J 0
(2260 2335);
DISPLAY 0.680851 (2260 2335);
PAINT MONO (2260 2335);
FORCEPROP 0 LASTPIN (2250 2425) $PN EE5
J 0
(2260 2435);
DISPLAY 0.680851 (2260 2435);
PAINT MONO (2260 2435);
FORCEPROP 0 LASTPIN (2250 2475) $PN ED6
J 0
(2260 2485);
DISPLAY 0.680851 (2260 2485);
PAINT MONO (2260 2485);
FORCEPROP 0 LASTPIN (2250 2525) $PN EA5
J 0
(2260 2535);
DISPLAY 0.680851 (2260 2535);
PAINT MONO (2260 2535);
FORCEPROP 0 LASTPIN (2250 2575) $PN DW7
J 0
(2260 2585);
DISPLAY 0.680851 (2260 2585);
PAINT MONO (2260 2585);
FORCEPROP 0 LASTPIN (2250 2625) $PN DU5
J 0
(2260 2635);
DISPLAY 0.680851 (2260 2635);
PAINT MONO (2260 2635);
FORCEPROP 0 LASTPIN (2250 2675) $PN DR7
J 0
(2260 2685);
DISPLAY 0.680851 (2260 2685);
PAINT MONO (2260 2685);
FORCEPROP 0 LASTPIN (2250 2725) $PN DN5
J 0
(2260 2735);
DISPLAY 0.680851 (2260 2735);
PAINT MONO (2260 2735);
FORCEPROP 0 LASTPIN (2250 2775) $PN DM6
J 0
(2260 2785);
DISPLAY 0.680851 (2260 2785);
PAINT MONO (2260 2785);
FORCEPROP 0 LASTPIN (2250 2825) $PN DJ5
J 0
(2260 2835);
DISPLAY 0.680851 (2260 2835);
PAINT MONO (2260 2835);
FORCEPROP 0 LASTPIN (2250 2875) $PN DG7
J 0
(2260 2885);
DISPLAY 0.680851 (2260 2885);
PAINT MONO (2260 2885);
FORCEPROP 0 LASTPIN (2250 2925) $PN DF6
J 0
(2260 2935);
DISPLAY 0.680851 (2260 2935);
PAINT MONO (2260 2935);
FORCEPROP 0 LASTPIN (2250 2975) $PN DC7
J 0
(2260 2985);
DISPLAY 0.680851 (2260 2985);
PAINT MONO (2260 2985);
FORCEPROP 0 LASTPIN (2250 3025) $PN DB6
J 0
(2260 3035);
DISPLAY 0.680851 (2260 3035);
PAINT MONO (2260 3035);
FORCEPROP 0 LASTPIN (2250 3075) $PN CW7
J 0
(2260 3085);
DISPLAY 0.680851 (2260 3085);
PAINT MONO (2260 3085);
FORCEPROP 0 LASTPIN (2250 3125) $PN CV6
J 0
(2260 3135);
DISPLAY 0.680851 (2260 3135);
PAINT MONO (2260 3135);
FORCEPROP 0 LASTPIN (2250 3175) $PN CR7
J 0
(2260 3185);
DISPLAY 0.680851 (2260 3185);
PAINT MONO (2260 3185);
FORCEPROP 0 LASTPIN (2250 3225) $PN CP6
J 0
(2260 3235);
DISPLAY 0.680851 (2260 3235);
PAINT MONO (2260 3235);
FORCEPROP 0 LASTPIN (2250 3275) $PN CL7
J 0
(2260 3285);
DISPLAY 0.680851 (2260 3285);
PAINT MONO (2260 3285);
FORCEPROP 0 LASTPIN (2250 3325) $PN CK6
J 0
(2260 3335);
DISPLAY 0.680851 (2260 3335);
PAINT MONO (2260 3335);
FORCEPROP 0 LASTPIN (2250 3375) $PN CG7
J 0
(2260 3385);
DISPLAY 0.680851 (2260 3385);
PAINT MONO (2260 3385);
FORCEPROP 0 LASTPIN (2250 3425) $PN CF6
J 0
(2260 3435);
DISPLAY 0.680851 (2260 3435);
PAINT MONO (2260 3435);
FORCEPROP 0 LASTPIN (2250 3475) $PN CC7
J 0
(2260 3485);
DISPLAY 0.680851 (2260 3485);
PAINT MONO (2260 3485);
FORCEPROP 0 LASTPIN (2250 3525) $PN CB6
J 0
(2260 3535);
DISPLAY 0.680851 (2260 3535);
PAINT MONO (2260 3535);
FORCEPROP 0 LASTPIN (2250 3575) $PN BW7
J 0
(2260 3585);
DISPLAY 0.680851 (2260 3585);
PAINT MONO (2260 3585);
FORCEPROP 1 LAST CDS_LMAN_SYM_OUTLINE -1050,1350,1050,-1350
J 0
(1050 2375);
DISPLAY 0.468085 (1050 2375);
PAINT GREEN (1050 2375);
DISPLAY INVISIBLE (1050 2375);
FORCEPROP 1 LAST NEEDS_NO_SIZE TRUE
J 0
(1050 2375);
DISPLAY 0.723404 (1050 2375);
PAINT GREEN (1050 2375);
DISPLAY INVISIBLE (1050 2375);
FORCEPROP 2 LAST CDS_LIB pure_quanta
J 0
(1050 2375);
DISPLAY INVISIBLE (1050 2375);
FORCEPROP 2 LAST CDS_LOCATION U2
J 0
(0 4050);
DISPLAY 1.021277 (0 4050);
DISPLAY INVISIBLE (0 4050);
FORCEPROP 0 LAST $SEC 23
J 0
(0 4050);
DISPLAY 0.680851 (0 4050);
PAINT MONO (0 4050);
DISPLAY INVISIBLE (0 4050);
FORCEPROP 2 LAST CDS_SEC 23
J 0
(0 4050);
DISPLAY 1.021277 (0 4050);
DISPLAY INVISIBLE (0 4050);
FORCEPROP 1 LAST PATH I102
J 0
(1050 2375);
DISPLAY 0.723404 (1050 2375);
PAINT GREEN (1050 2375);
DISPLAY INVISIBLE (1050 2375);
FORCEADD TAP..1
R 2
(-850 3575);
FORCEPROP 3 LASTPIN (-800 3575) SIG_NAME UPI_CPU1_CPU0_P0P1_DN<23>
J 0
(-790 3585);
DISPLAY 0.659574 (-790 3585);
PAINT MONO (-790 3585);
DISPLAY INVISIBLE (-790 3585);
FORCEPROP 1 LASTPIN (-800 3575) BN 23
J 2
(-788 3583);
DISPLAY 0.680851 (-788 3583);
PAINT GREEN (-788 3583);
FORCEPROP 2 LAST CDS_LIB standard
J 0
(-850 3575);
DISPLAY INVISIBLE (-850 3575);
FORCEPROP 1 LAST BODY_TYPE PLUMBING
J 2
(-850 3625);
DISPLAY 0.872340 (-850 3625);
PAINT GREEN (-850 3625);
DISPLAY INVISIBLE (-850 3625);
FORCEPROP 1 LAST HDL_TAP TRUE
J 2
(-1175 3450);
DISPLAY 0.872340 (-1175 3450);
DISPLAY INVISIBLE (-1175 3450);
FORCEPROP 1 LAST PATH I103
J 2
(-848 3575);
DISPLAY 0.872340 (-848 3575);
PAINT GREEN (-848 3575);
DISPLAY INVISIBLE (-848 3575);
FORCEADD TAP..1
R 2
(-850 3525);
FORCEPROP 3 LASTPIN (-800 3525) SIG_NAME UPI_CPU1_CPU0_P0P1_DN<22>
J 0
(-790 3535);
DISPLAY 0.659574 (-790 3535);
PAINT MONO (-790 3535);
DISPLAY INVISIBLE (-790 3535);
FORCEPROP 1 LASTPIN (-800 3525) BN 22
J 2
(-788 3533);
DISPLAY 0.680851 (-788 3533);
PAINT GREEN (-788 3533);
FORCEPROP 2 LAST CDS_LIB standard
J 0
(-850 3525);
DISPLAY INVISIBLE (-850 3525);
FORCEPROP 1 LAST BODY_TYPE PLUMBING
J 2
(-850 3575);
DISPLAY 0.872340 (-850 3575);
PAINT GREEN (-850 3575);
DISPLAY INVISIBLE (-850 3575);
FORCEPROP 1 LAST HDL_TAP TRUE
J 2
(-1175 3400);
DISPLAY 0.872340 (-1175 3400);
DISPLAY INVISIBLE (-1175 3400);
FORCEPROP 1 LAST PATH I104
J 2
(-848 3525);
DISPLAY 0.872340 (-848 3525);
PAINT GREEN (-848 3525);
DISPLAY INVISIBLE (-848 3525);
FORCEADD TAP..1
R 2
(-850 3425);
FORCEPROP 3 LASTPIN (-800 3425) SIG_NAME UPI_CPU1_CPU0_P0P1_DN<20>
J 0
(-790 3435);
DISPLAY 0.659574 (-790 3435);
PAINT MONO (-790 3435);
DISPLAY INVISIBLE (-790 3435);
FORCEPROP 1 LASTPIN (-800 3425) BN 20
J 2
(-788 3433);
DISPLAY 0.680851 (-788 3433);
PAINT GREEN (-788 3433);
FORCEPROP 2 LAST CDS_LIB standard
J 0
(-850 3425);
DISPLAY INVISIBLE (-850 3425);
FORCEPROP 1 LAST BODY_TYPE PLUMBING
J 2
(-850 3475);
DISPLAY 0.872340 (-850 3475);
PAINT GREEN (-850 3475);
DISPLAY INVISIBLE (-850 3475);
FORCEPROP 1 LAST HDL_TAP TRUE
J 2
(-1175 3300);
DISPLAY 0.872340 (-1175 3300);
DISPLAY INVISIBLE (-1175 3300);
FORCEPROP 1 LAST PATH I105
J 2
(-848 3425);
DISPLAY 0.872340 (-848 3425);
PAINT GREEN (-848 3425);
DISPLAY INVISIBLE (-848 3425);
FORCEADD TAP..1
R 2
(-850 3375);
FORCEPROP 3 LASTPIN (-800 3375) SIG_NAME UPI_CPU1_CPU0_P0P1_DN<19>
J 0
(-790 3385);
DISPLAY 0.659574 (-790 3385);
PAINT MONO (-790 3385);
DISPLAY INVISIBLE (-790 3385);
FORCEPROP 1 LASTPIN (-800 3375) BN 19
J 2
(-788 3383);
DISPLAY 0.680851 (-788 3383);
PAINT GREEN (-788 3383);
FORCEPROP 2 LAST CDS_LIB standard
J 0
(-850 3375);
DISPLAY INVISIBLE (-850 3375);
FORCEPROP 1 LAST BODY_TYPE PLUMBING
J 2
(-850 3425);
DISPLAY 0.872340 (-850 3425);
PAINT GREEN (-850 3425);
DISPLAY INVISIBLE (-850 3425);
FORCEPROP 1 LAST HDL_TAP TRUE
J 2
(-1175 3250);
DISPLAY 0.872340 (-1175 3250);
DISPLAY INVISIBLE (-1175 3250);
FORCEPROP 1 LAST PATH I106
J 2
(-848 3375);
DISPLAY 0.872340 (-848 3375);
PAINT GREEN (-848 3375);
DISPLAY INVISIBLE (-848 3375);
FORCEADD TAP..1
R 2
(-850 3275);
FORCEPROP 3 LASTPIN (-800 3275) SIG_NAME UPI_CPU1_CPU0_P0P1_DN<17>
J 0
(-790 3285);
DISPLAY 0.659574 (-790 3285);
PAINT MONO (-790 3285);
DISPLAY INVISIBLE (-790 3285);
FORCEPROP 1 LASTPIN (-800 3275) BN 17
J 2
(-788 3283);
DISPLAY 0.680851 (-788 3283);
PAINT GREEN (-788 3283);
FORCEPROP 2 LAST CDS_LIB standard
J 0
(-850 3275);
DISPLAY INVISIBLE (-850 3275);
FORCEPROP 1 LAST BODY_TYPE PLUMBING
J 2
(-850 3325);
DISPLAY 0.872340 (-850 3325);
PAINT GREEN (-850 3325);
DISPLAY INVISIBLE (-850 3325);
FORCEPROP 1 LAST HDL_TAP TRUE
J 2
(-1175 3150);
DISPLAY 0.872340 (-1175 3150);
DISPLAY INVISIBLE (-1175 3150);
FORCEPROP 1 LAST PATH I107
J 2
(-848 3275);
DISPLAY 0.872340 (-848 3275);
PAINT GREEN (-848 3275);
DISPLAY INVISIBLE (-848 3275);
FORCEADD TAP..1
R 2
(-850 3025);
FORCEPROP 3 LASTPIN (-800 3025) SIG_NAME UPI_CPU1_CPU0_P0P1_DN<12>
J 0
(-790 3035);
DISPLAY 0.659574 (-790 3035);
PAINT MONO (-790 3035);
DISPLAY INVISIBLE (-790 3035);
FORCEPROP 1 LASTPIN (-800 3025) BN 12
J 2
(-788 3033);
DISPLAY 0.680851 (-788 3033);
PAINT GREEN (-788 3033);
FORCEPROP 2 LAST CDS_LIB standard
J 0
(-850 3025);
DISPLAY INVISIBLE (-850 3025);
FORCEPROP 1 LAST BODY_TYPE PLUMBING
J 2
(-850 3075);
DISPLAY 0.872340 (-850 3075);
PAINT GREEN (-850 3075);
DISPLAY INVISIBLE (-850 3075);
FORCEPROP 1 LAST HDL_TAP TRUE
J 2
(-1175 2900);
DISPLAY 0.872340 (-1175 2900);
DISPLAY INVISIBLE (-1175 2900);
FORCEPROP 1 LAST PATH I108
J 2
(-848 3025);
DISPLAY 0.872340 (-848 3025);
PAINT GREEN (-848 3025);
DISPLAY INVISIBLE (-848 3025);
FORCEADD TAP..1
R 2
(-650 2325);
FORCEPROP 3 LASTPIN (-600 2325) SIG_NAME UPI_CPU1_CPU0_P0P1_DP<23>
J 0
(-590 2335);
DISPLAY 0.659574 (-590 2335);
PAINT MONO (-590 2335);
DISPLAY INVISIBLE (-590 2335);
FORCEPROP 1 LASTPIN (-600 2325) BN 23
J 2
(-588 2333);
DISPLAY 0.680851 (-588 2333);
PAINT GREEN (-588 2333);
FORCEPROP 2 LAST CDS_LIB standard
J 0
(-650 2325);
PAINT MONO (-650 2325);
DISPLAY INVISIBLE (-650 2325);
FORCEPROP 1 LAST BODY_TYPE PLUMBING
J 2
(-650 2375);
DISPLAY 0.872340 (-650 2375);
PAINT GREEN (-650 2375);
DISPLAY INVISIBLE (-650 2375);
FORCEPROP 1 LAST HDL_TAP TRUE
J 2
(-975 2200);
DISPLAY 0.872340 (-975 2200);
DISPLAY INVISIBLE (-975 2200);
FORCEPROP 1 LAST PATH I109
J 2
(-648 2325);
DISPLAY 0.872340 (-648 2325);
PAINT GREEN (-648 2325);
DISPLAY INVISIBLE (-648 2325);
FORCEADD TAP..1
R 2
(-850 1675);
FORCEPROP 3 LASTPIN (-800 1675) SIG_NAME UPI_CPU1_CPU0_P0P1_DN<10>
J 0
(-790 1685);
DISPLAY 0.659574 (-790 1685);
PAINT MONO (-790 1685);
DISPLAY INVISIBLE (-790 1685);
FORCEPROP 1 LASTPIN (-800 1675) BN 10
J 2
(-788 1683);
DISPLAY 0.680851 (-788 1683);
PAINT GREEN (-788 1683);
FORCEPROP 2 LAST CDS_LIB standard
J 0
(-850 1675);
DISPLAY INVISIBLE (-850 1675);
FORCEPROP 1 LAST BODY_TYPE PLUMBING
J 2
(-850 1725);
DISPLAY 0.872340 (-850 1725);
PAINT GREEN (-850 1725);
DISPLAY INVISIBLE (-850 1725);
FORCEPROP 1 LAST HDL_TAP TRUE
J 2
(-1175 1550);
DISPLAY 0.872340 (-1175 1550);
DISPLAY INVISIBLE (-1175 1550);
FORCEPROP 1 LAST PATH I11
J 2
(-848 1675);
DISPLAY 0.872340 (-848 1675);
PAINT GREEN (-848 1675);
DISPLAY INVISIBLE (-848 1675);
FORCEADD TAP..1
R 2
(-650 2125);
FORCEPROP 3 LASTPIN (-600 2125) SIG_NAME UPI_CPU1_CPU0_P0P1_DP<19>
J 0
(-590 2135);
DISPLAY 0.659574 (-590 2135);
PAINT MONO (-590 2135);
DISPLAY INVISIBLE (-590 2135);
FORCEPROP 1 LASTPIN (-600 2125) BN 19
J 2
(-588 2133);
DISPLAY 0.680851 (-588 2133);
PAINT GREEN (-588 2133);
FORCEPROP 2 LAST CDS_LIB standard
J 0
(-650 2125);
PAINT MONO (-650 2125);
DISPLAY INVISIBLE (-650 2125);
FORCEPROP 1 LAST BODY_TYPE PLUMBING
J 2
(-650 2175);
DISPLAY 0.872340 (-650 2175);
PAINT GREEN (-650 2175);
DISPLAY INVISIBLE (-650 2175);
FORCEPROP 1 LAST HDL_TAP TRUE
J 2
(-975 2000);
DISPLAY 0.872340 (-975 2000);
DISPLAY INVISIBLE (-975 2000);
FORCEPROP 1 LAST PATH I111
J 2
(-648 2125);
DISPLAY 0.872340 (-648 2125);
PAINT GREEN (-648 2125);
DISPLAY INVISIBLE (-648 2125);
FORCEADD TAP..1
R 2
(-850 2075);
FORCEPROP 3 LASTPIN (-800 2075) SIG_NAME UPI_CPU1_CPU0_P0P1_DN<18>
J 0
(-790 2085);
DISPLAY 0.659574 (-790 2085);
PAINT MONO (-790 2085);
DISPLAY INVISIBLE (-790 2085);
FORCEPROP 1 LASTPIN (-800 2075) BN 18
J 2
(-788 2083);
DISPLAY 0.680851 (-788 2083);
PAINT GREEN (-788 2083);
FORCEPROP 2 LAST CDS_LIB standard
J 0
(-850 2075);
PAINT MONO (-850 2075);
DISPLAY INVISIBLE (-850 2075);
FORCEPROP 1 LAST BODY_TYPE PLUMBING
J 2
(-850 2125);
DISPLAY 0.872340 (-850 2125);
PAINT GREEN (-850 2125);
DISPLAY INVISIBLE (-850 2125);
FORCEPROP 1 LAST HDL_TAP TRUE
J 2
(-1175 1950);
DISPLAY 0.872340 (-1175 1950);
DISPLAY INVISIBLE (-1175 1950);
FORCEPROP 1 LAST PATH I112
J 2
(-848 2075);
DISPLAY 0.872340 (-848 2075);
PAINT GREEN (-848 2075);
DISPLAY INVISIBLE (-848 2075);
FORCEADD TAP..1
(2725 2175);
FORCEPROP 3 LASTPIN (2675 2175) SIG_NAME UPI_CPU0_CPU1_P1P0_DP<20>
J 0
(2685 2185);
DISPLAY 0.659574 (2685 2185);
PAINT MONO (2685 2185);
DISPLAY INVISIBLE (2685 2185);
FORCEPROP 1 LASTPIN (2675 2175) BN 20
J 0
(2663 2183);
DISPLAY 0.680851 (2663 2183);
PAINT GREEN (2663 2183);
FORCEPROP 2 LAST CDS_LIB standard
J 0
(2725 2175);
DISPLAY INVISIBLE (2725 2175);
FORCEPROP 1 LAST BODY_TYPE PLUMBING
J 0
(2725 2225);
DISPLAY 0.872340 (2725 2225);
PAINT GREEN (2725 2225);
DISPLAY INVISIBLE (2725 2225);
FORCEPROP 1 LAST HDL_TAP TRUE
J 0
(3050 2050);
DISPLAY 0.872340 (3050 2050);
DISPLAY INVISIBLE (3050 2050);
FORCEPROP 1 LAST PATH I113
J 0
(2723 2175);
DISPLAY 0.872340 (2723 2175);
PAINT GREEN (2723 2175);
DISPLAY INVISIBLE (2723 2175);
FORCEADD TAP..1
(2725 2225);
FORCEPROP 3 LASTPIN (2675 2225) SIG_NAME UPI_CPU0_CPU1_P1P0_DP<21>
J 0
(2685 2235);
DISPLAY 0.659574 (2685 2235);
PAINT MONO (2685 2235);
DISPLAY INVISIBLE (2685 2235);
FORCEPROP 1 LASTPIN (2675 2225) BN 21
J 0
(2663 2233);
DISPLAY 0.680851 (2663 2233);
PAINT GREEN (2663 2233);
FORCEPROP 2 LAST CDS_LIB standard
J 0
(2725 2225);
DISPLAY INVISIBLE (2725 2225);
FORCEPROP 1 LAST BODY_TYPE PLUMBING
J 0
(2725 2275);
DISPLAY 0.872340 (2725 2275);
PAINT GREEN (2725 2275);
DISPLAY INVISIBLE (2725 2275);
FORCEPROP 1 LAST HDL_TAP TRUE
J 0
(3050 2100);
DISPLAY 0.872340 (3050 2100);
DISPLAY INVISIBLE (3050 2100);
FORCEPROP 1 LAST PATH I114
J 0
(2723 2225);
DISPLAY 0.872340 (2723 2225);
PAINT GREEN (2723 2225);
DISPLAY INVISIBLE (2723 2225);
FORCEADD TAP..1
(2725 2325);
FORCEPROP 3 LASTPIN (2675 2325) SIG_NAME UPI_CPU0_CPU1_P1P0_DP<23>
J 0
(2685 2335);
DISPLAY 0.659574 (2685 2335);
PAINT MONO (2685 2335);
DISPLAY INVISIBLE (2685 2335);
FORCEPROP 1 LASTPIN (2675 2325) BN 23
J 0
(2663 2333);
DISPLAY 0.680851 (2663 2333);
PAINT GREEN (2663 2333);
FORCEPROP 2 LAST CDS_LIB standard
J 0
(2725 2325);
DISPLAY INVISIBLE (2725 2325);
FORCEPROP 1 LAST BODY_TYPE PLUMBING
J 0
(2725 2375);
DISPLAY 0.872340 (2725 2375);
PAINT GREEN (2725 2375);
DISPLAY INVISIBLE (2725 2375);
FORCEPROP 1 LAST HDL_TAP TRUE
J 0
(3050 2200);
DISPLAY 0.872340 (3050 2200);
DISPLAY INVISIBLE (3050 2200);
FORCEPROP 1 LAST PATH I115
J 0
(2723 2325);
DISPLAY 0.872340 (2723 2325);
PAINT GREEN (2723 2325);
DISPLAY INVISIBLE (2723 2325);
FORCEADD TAP..1
(2725 1325);
FORCEPROP 3 LASTPIN (2675 1325) SIG_NAME UPI_CPU0_CPU1_P1P0_DP<3>
J 0
(2685 1335);
DISPLAY 0.659574 (2685 1335);
PAINT MONO (2685 1335);
DISPLAY INVISIBLE (2685 1335);
FORCEPROP 1 LASTPIN (2675 1325) BN 3
J 0
(2663 1333);
DISPLAY 0.680851 (2663 1333);
PAINT GREEN (2663 1333);
FORCEPROP 2 LAST CDS_LIB standard
J 0
(2725 1325);
PAINT MONO (2725 1325);
DISPLAY INVISIBLE (2725 1325);
FORCEPROP 1 LAST BODY_TYPE PLUMBING
J 0
(2725 1375);
DISPLAY 0.872340 (2725 1375);
PAINT GREEN (2725 1375);
DISPLAY INVISIBLE (2725 1375);
FORCEPROP 1 LAST HDL_TAP TRUE
J 0
(3050 1200);
DISPLAY 0.872340 (3050 1200);
DISPLAY INVISIBLE (3050 1200);
FORCEPROP 1 LAST PATH I116
J 0
(2723 1325);
DISPLAY 0.872340 (2723 1325);
PAINT GREEN (2723 1325);
DISPLAY INVISIBLE (2723 1325);
FORCEADD TAP..1
(2725 1425);
FORCEPROP 3 LASTPIN (2675 1425) SIG_NAME UPI_CPU0_CPU1_P1P0_DP<5>
J 0
(2685 1435);
DISPLAY 0.659574 (2685 1435);
PAINT MONO (2685 1435);
DISPLAY INVISIBLE (2685 1435);
FORCEPROP 1 LASTPIN (2675 1425) BN 5
J 0
(2663 1433);
DISPLAY 0.680851 (2663 1433);
PAINT GREEN (2663 1433);
FORCEPROP 2 LAST CDS_LIB standard
J 0
(2725 1425);
PAINT MONO (2725 1425);
DISPLAY INVISIBLE (2725 1425);
FORCEPROP 1 LAST BODY_TYPE PLUMBING
J 0
(2725 1475);
DISPLAY 0.872340 (2725 1475);
PAINT GREEN (2725 1475);
DISPLAY INVISIBLE (2725 1475);
FORCEPROP 1 LAST HDL_TAP TRUE
J 0
(3050 1300);
DISPLAY 0.872340 (3050 1300);
DISPLAY INVISIBLE (3050 1300);
FORCEPROP 1 LAST PATH I117
J 0
(2723 1425);
DISPLAY 0.872340 (2723 1425);
PAINT GREEN (2723 1425);
DISPLAY INVISIBLE (2723 1425);
FORCEADD TAP..1
(2725 1675);
FORCEPROP 3 LASTPIN (2675 1675) SIG_NAME UPI_CPU0_CPU1_P1P0_DP<10>
J 0
(2685 1685);
DISPLAY 0.659574 (2685 1685);
PAINT MONO (2685 1685);
DISPLAY INVISIBLE (2685 1685);
FORCEPROP 1 LASTPIN (2675 1675) BN 10
J 0
(2663 1683);
DISPLAY 0.680851 (2663 1683);
PAINT GREEN (2663 1683);
FORCEPROP 2 LAST CDS_LIB standard
J 0
(2725 1675);
PAINT MONO (2725 1675);
DISPLAY INVISIBLE (2725 1675);
FORCEPROP 1 LAST BODY_TYPE PLUMBING
J 0
(2725 1725);
DISPLAY 0.872340 (2725 1725);
PAINT GREEN (2725 1725);
DISPLAY INVISIBLE (2725 1725);
FORCEPROP 1 LAST HDL_TAP TRUE
J 0
(3050 1550);
DISPLAY 0.872340 (3050 1550);
DISPLAY INVISIBLE (3050 1550);
FORCEPROP 1 LAST PATH I118
J 0
(2723 1675);
DISPLAY 0.872340 (2723 1675);
PAINT GREEN (2723 1675);
DISPLAY INVISIBLE (2723 1675);
FORCEADD TAP..1
(2725 1725);
FORCEPROP 3 LASTPIN (2675 1725) SIG_NAME UPI_CPU0_CPU1_P1P0_DP<11>
J 0
(2685 1735);
DISPLAY 0.659574 (2685 1735);
PAINT MONO (2685 1735);
DISPLAY INVISIBLE (2685 1735);
FORCEPROP 1 LASTPIN (2675 1725) BN 11
J 0
(2663 1733);
DISPLAY 0.680851 (2663 1733);
PAINT GREEN (2663 1733);
FORCEPROP 2 LAST CDS_LIB standard
J 0
(2725 1725);
PAINT MONO (2725 1725);
DISPLAY INVISIBLE (2725 1725);
FORCEPROP 1 LAST BODY_TYPE PLUMBING
J 0
(2725 1775);
DISPLAY 0.872340 (2725 1775);
PAINT GREEN (2725 1775);
DISPLAY INVISIBLE (2725 1775);
FORCEPROP 1 LAST HDL_TAP TRUE
J 0
(3050 1600);
DISPLAY 0.872340 (3050 1600);
DISPLAY INVISIBLE (3050 1600);
FORCEPROP 1 LAST PATH I119
J 0
(2723 1725);
DISPLAY 0.872340 (2723 1725);
PAINT GREEN (2723 1725);
DISPLAY INVISIBLE (2723 1725);
FORCEADD TAP..1
R 2
(-650 1775);
FORCEPROP 3 LASTPIN (-600 1775) SIG_NAME UPI_CPU1_CPU0_P0P1_DP<12>
J 0
(-590 1785);
DISPLAY 0.659574 (-590 1785);
PAINT MONO (-590 1785);
DISPLAY INVISIBLE (-590 1785);
FORCEPROP 1 LASTPIN (-600 1775) BN 12
J 2
(-588 1783);
DISPLAY 0.680851 (-588 1783);
PAINT GREEN (-588 1783);
FORCEPROP 2 LAST CDS_LIB standard
J 0
(-650 1775);
DISPLAY INVISIBLE (-650 1775);
FORCEPROP 1 LAST BODY_TYPE PLUMBING
J 2
(-650 1825);
DISPLAY 0.872340 (-650 1825);
PAINT GREEN (-650 1825);
DISPLAY INVISIBLE (-650 1825);
FORCEPROP 1 LAST HDL_TAP TRUE
J 2
(-975 1650);
DISPLAY 0.872340 (-975 1650);
DISPLAY INVISIBLE (-975 1650);
FORCEPROP 1 LAST PATH I12
J 2
(-648 1775);
DISPLAY 0.872340 (-648 1775);
PAINT GREEN (-648 1775);
DISPLAY INVISIBLE (-648 1775);
FORCEADD TAP..1
(2725 1775);
FORCEPROP 3 LASTPIN (2675 1775) SIG_NAME UPI_CPU0_CPU1_P1P0_DP<12>
J 0
(2685 1785);
DISPLAY 0.659574 (2685 1785);
PAINT MONO (2685 1785);
DISPLAY INVISIBLE (2685 1785);
FORCEPROP 1 LASTPIN (2675 1775) BN 12
J 0
(2663 1783);
DISPLAY 0.680851 (2663 1783);
PAINT GREEN (2663 1783);
FORCEPROP 2 LAST CDS_LIB standard
J 0
(2725 1775);
PAINT MONO (2725 1775);
DISPLAY INVISIBLE (2725 1775);
FORCEPROP 1 LAST BODY_TYPE PLUMBING
J 0
(2725 1825);
DISPLAY 0.872340 (2725 1825);
PAINT GREEN (2725 1825);
DISPLAY INVISIBLE (2725 1825);
FORCEPROP 1 LAST HDL_TAP TRUE
J 0
(3050 1650);
DISPLAY 0.872340 (3050 1650);
DISPLAY INVISIBLE (3050 1650);
FORCEPROP 1 LAST PATH I120
J 0
(2723 1775);
DISPLAY 0.872340 (2723 1775);
PAINT GREEN (2723 1775);
DISPLAY INVISIBLE (2723 1775);
FORCEADD TAP..1
(2725 1825);
FORCEPROP 3 LASTPIN (2675 1825) SIG_NAME UPI_CPU0_CPU1_P1P0_DP<13>
J 0
(2685 1835);
DISPLAY 0.659574 (2685 1835);
PAINT MONO (2685 1835);
DISPLAY INVISIBLE (2685 1835);
FORCEPROP 1 LASTPIN (2675 1825) BN 13
J 0
(2663 1833);
DISPLAY 0.680851 (2663 1833);
PAINT GREEN (2663 1833);
FORCEPROP 2 LAST CDS_LIB standard
J 0
(2725 1825);
PAINT MONO (2725 1825);
DISPLAY INVISIBLE (2725 1825);
FORCEPROP 1 LAST BODY_TYPE PLUMBING
J 0
(2725 1875);
DISPLAY 0.872340 (2725 1875);
PAINT GREEN (2725 1875);
DISPLAY INVISIBLE (2725 1875);
FORCEPROP 1 LAST HDL_TAP TRUE
J 0
(3050 1700);
DISPLAY 0.872340 (3050 1700);
DISPLAY INVISIBLE (3050 1700);
FORCEPROP 1 LAST PATH I121
J 0
(2723 1825);
DISPLAY 0.872340 (2723 1825);
PAINT GREEN (2723 1825);
DISPLAY INVISIBLE (2723 1825);
FORCEADD TAP..1
(2725 1925);
FORCEPROP 3 LASTPIN (2675 1925) SIG_NAME UPI_CPU0_CPU1_P1P0_DP<15>
J 0
(2685 1935);
DISPLAY 0.659574 (2685 1935);
PAINT MONO (2685 1935);
DISPLAY INVISIBLE (2685 1935);
FORCEPROP 1 LASTPIN (2675 1925) BN 15
J 0
(2663 1933);
DISPLAY 0.680851 (2663 1933);
PAINT GREEN (2663 1933);
FORCEPROP 2 LAST CDS_LIB standard
J 0
(2725 1925);
PAINT MONO (2725 1925);
DISPLAY INVISIBLE (2725 1925);
FORCEPROP 1 LAST BODY_TYPE PLUMBING
J 0
(2725 1975);
DISPLAY 0.872340 (2725 1975);
PAINT GREEN (2725 1975);
DISPLAY INVISIBLE (2725 1975);
FORCEPROP 1 LAST HDL_TAP TRUE
J 0
(3050 1800);
DISPLAY 0.872340 (3050 1800);
DISPLAY INVISIBLE (3050 1800);
FORCEPROP 1 LAST PATH I122
J 0
(2723 1925);
DISPLAY 0.872340 (2723 1925);
PAINT GREEN (2723 1925);
DISPLAY INVISIBLE (2723 1925);
FORCEADD TAP..1
(2725 1975);
FORCEPROP 3 LASTPIN (2675 1975) SIG_NAME UPI_CPU0_CPU1_P1P0_DP<16>
J 0
(2685 1985);
DISPLAY 0.659574 (2685 1985);
PAINT MONO (2685 1985);
DISPLAY INVISIBLE (2685 1985);
FORCEPROP 1 LASTPIN (2675 1975) BN 16
J 0
(2663 1983);
DISPLAY 0.680851 (2663 1983);
PAINT GREEN (2663 1983);
FORCEPROP 2 LAST CDS_LIB standard
J 0
(2725 1975);
PAINT MONO (2725 1975);
DISPLAY INVISIBLE (2725 1975);
FORCEPROP 1 LAST BODY_TYPE PLUMBING
J 0
(2725 2025);
DISPLAY 0.872340 (2725 2025);
PAINT GREEN (2725 2025);
DISPLAY INVISIBLE (2725 2025);
FORCEPROP 1 LAST HDL_TAP TRUE
J 0
(3050 1850);
DISPLAY 0.872340 (3050 1850);
DISPLAY INVISIBLE (3050 1850);
FORCEPROP 1 LAST PATH I123
J 0
(2723 1975);
DISPLAY 0.872340 (2723 1975);
PAINT GREEN (2723 1975);
DISPLAY INVISIBLE (2723 1975);
FORCEADD TAP..1
(2725 2025);
FORCEPROP 3 LASTPIN (2675 2025) SIG_NAME UPI_CPU0_CPU1_P1P0_DP<17>
J 0
(2685 2035);
DISPLAY 0.659574 (2685 2035);
PAINT MONO (2685 2035);
DISPLAY INVISIBLE (2685 2035);
FORCEPROP 1 LASTPIN (2675 2025) BN 17
J 0
(2663 2033);
DISPLAY 0.680851 (2663 2033);
PAINT GREEN (2663 2033);
FORCEPROP 2 LAST CDS_LIB standard
J 0
(2725 2025);
DISPLAY INVISIBLE (2725 2025);
FORCEPROP 1 LAST BODY_TYPE PLUMBING
J 0
(2725 2075);
DISPLAY 0.872340 (2725 2075);
PAINT GREEN (2725 2075);
DISPLAY INVISIBLE (2725 2075);
FORCEPROP 1 LAST HDL_TAP TRUE
J 0
(3050 1900);
DISPLAY 0.872340 (3050 1900);
DISPLAY INVISIBLE (3050 1900);
FORCEPROP 1 LAST PATH I124
J 0
(2723 2025);
DISPLAY 0.872340 (2723 2025);
PAINT GREEN (2723 2025);
DISPLAY INVISIBLE (2723 2025);
FORCEADD TAP..1
(2725 2125);
FORCEPROP 3 LASTPIN (2675 2125) SIG_NAME UPI_CPU0_CPU1_P1P0_DP<19>
J 0
(2685 2135);
DISPLAY 0.659574 (2685 2135);
PAINT MONO (2685 2135);
DISPLAY INVISIBLE (2685 2135);
FORCEPROP 1 LASTPIN (2675 2125) BN 19
J 0
(2663 2133);
DISPLAY 0.680851 (2663 2133);
PAINT GREEN (2663 2133);
FORCEPROP 2 LAST CDS_LIB standard
J 0
(2725 2125);
DISPLAY INVISIBLE (2725 2125);
FORCEPROP 1 LAST BODY_TYPE PLUMBING
J 0
(2725 2175);
DISPLAY 0.872340 (2725 2175);
PAINT GREEN (2725 2175);
DISPLAY INVISIBLE (2725 2175);
FORCEPROP 1 LAST HDL_TAP TRUE
J 0
(3050 2000);
DISPLAY 0.872340 (3050 2000);
DISPLAY INVISIBLE (3050 2000);
FORCEPROP 1 LAST PATH I125
J 0
(2723 2125);
DISPLAY 0.872340 (2723 2125);
PAINT GREEN (2723 2125);
DISPLAY INVISIBLE (2723 2125);
FORCEADD TAP..1
(2925 2575);
FORCEPROP 3 LASTPIN (2875 2575) SIG_NAME UPI_CPU0_CPU1_P1P0_DN<3>
J 0
(2885 2585);
DISPLAY 0.659574 (2885 2585);
PAINT MONO (2885 2585);
DISPLAY INVISIBLE (2885 2585);
FORCEPROP 1 LASTPIN (2875 2575) BN 3
J 0
(2863 2583);
DISPLAY 0.680851 (2863 2583);
PAINT GREEN (2863 2583);
FORCEPROP 2 LAST CDS_LIB standard
J 0
(2925 2575);
PAINT MONO (2925 2575);
DISPLAY INVISIBLE (2925 2575);
FORCEPROP 1 LAST BODY_TYPE PLUMBING
J 0
(2925 2625);
DISPLAY 0.872340 (2925 2625);
PAINT GREEN (2925 2625);
DISPLAY INVISIBLE (2925 2625);
FORCEPROP 1 LAST HDL_TAP TRUE
J 0
(3250 2450);
DISPLAY 0.872340 (3250 2450);
DISPLAY INVISIBLE (3250 2450);
FORCEPROP 1 LAST PATH I126
J 0
(2923 2575);
DISPLAY 0.872340 (2923 2575);
PAINT GREEN (2923 2575);
DISPLAY INVISIBLE (2923 2575);
FORCEADD TAP..1
(2925 2675);
FORCEPROP 3 LASTPIN (2875 2675) SIG_NAME UPI_CPU0_CPU1_P1P0_DN<5>
J 0
(2885 2685);
DISPLAY 0.659574 (2885 2685);
PAINT MONO (2885 2685);
DISPLAY INVISIBLE (2885 2685);
FORCEPROP 1 LASTPIN (2875 2675) BN 5
J 0
(2863 2683);
DISPLAY 0.680851 (2863 2683);
PAINT GREEN (2863 2683);
FORCEPROP 2 LAST CDS_LIB standard
J 0
(2925 2675);
PAINT MONO (2925 2675);
DISPLAY INVISIBLE (2925 2675);
FORCEPROP 1 LAST BODY_TYPE PLUMBING
J 0
(2925 2725);
DISPLAY 0.872340 (2925 2725);
PAINT GREEN (2925 2725);
DISPLAY INVISIBLE (2925 2725);
FORCEPROP 1 LAST HDL_TAP TRUE
J 0
(3250 2550);
DISPLAY 0.872340 (3250 2550);
DISPLAY INVISIBLE (3250 2550);
FORCEPROP 1 LAST PATH I127
J 0
(2923 2675);
DISPLAY 0.872340 (2923 2675);
PAINT GREEN (2923 2675);
DISPLAY INVISIBLE (2923 2675);
FORCEADD TAP..1
(2925 2925);
FORCEPROP 3 LASTPIN (2875 2925) SIG_NAME UPI_CPU0_CPU1_P1P0_DN<10>
J 0
(2885 2935);
DISPLAY 0.659574 (2885 2935);
PAINT MONO (2885 2935);
DISPLAY INVISIBLE (2885 2935);
FORCEPROP 1 LASTPIN (2875 2925) BN 10
J 0
(2863 2933);
DISPLAY 0.680851 (2863 2933);
PAINT GREEN (2863 2933);
FORCEPROP 2 LAST CDS_LIB standard
J 0
(2925 2925);
PAINT MONO (2925 2925);
DISPLAY INVISIBLE (2925 2925);
FORCEPROP 1 LAST BODY_TYPE PLUMBING
J 0
(2925 2975);
DISPLAY 0.872340 (2925 2975);
PAINT GREEN (2925 2975);
DISPLAY INVISIBLE (2925 2975);
FORCEPROP 1 LAST HDL_TAP TRUE
J 0
(3250 2800);
DISPLAY 0.872340 (3250 2800);
DISPLAY INVISIBLE (3250 2800);
FORCEPROP 1 LAST PATH I128
J 0
(2923 2925);
DISPLAY 0.872340 (2923 2925);
PAINT GREEN (2923 2925);
DISPLAY INVISIBLE (2923 2925);
FORCEADD TAP..1
(2925 2975);
FORCEPROP 3 LASTPIN (2875 2975) SIG_NAME UPI_CPU0_CPU1_P1P0_DN<11>
J 0
(2885 2985);
DISPLAY 0.659574 (2885 2985);
PAINT MONO (2885 2985);
DISPLAY INVISIBLE (2885 2985);
FORCEPROP 1 LASTPIN (2875 2975) BN 11
J 0
(2863 2983);
DISPLAY 0.680851 (2863 2983);
PAINT GREEN (2863 2983);
FORCEPROP 2 LAST CDS_LIB standard
J 0
(2925 2975);
PAINT MONO (2925 2975);
DISPLAY INVISIBLE (2925 2975);
FORCEPROP 1 LAST BODY_TYPE PLUMBING
J 0
(2925 3025);
DISPLAY 0.872340 (2925 3025);
PAINT GREEN (2925 3025);
DISPLAY INVISIBLE (2925 3025);
FORCEPROP 1 LAST HDL_TAP TRUE
J 0
(3250 2850);
DISPLAY 0.872340 (3250 2850);
DISPLAY INVISIBLE (3250 2850);
FORCEPROP 1 LAST PATH I129
J 0
(2923 2975);
DISPLAY 0.872340 (2923 2975);
PAINT GREEN (2923 2975);
DISPLAY INVISIBLE (2923 2975);
FORCEADD TAP..1
R 2
(-850 1725);
FORCEPROP 3 LASTPIN (-800 1725) SIG_NAME UPI_CPU1_CPU0_P0P1_DN<11>
J 0
(-790 1735);
DISPLAY 0.659574 (-790 1735);
PAINT MONO (-790 1735);
DISPLAY INVISIBLE (-790 1735);
FORCEPROP 1 LASTPIN (-800 1725) BN 11
J 2
(-788 1733);
DISPLAY 0.680851 (-788 1733);
PAINT GREEN (-788 1733);
FORCEPROP 2 LAST CDS_LIB standard
J 0
(-850 1725);
DISPLAY INVISIBLE (-850 1725);
FORCEPROP 1 LAST BODY_TYPE PLUMBING
J 2
(-850 1775);
DISPLAY 0.872340 (-850 1775);
PAINT GREEN (-850 1775);
DISPLAY INVISIBLE (-850 1775);
FORCEPROP 1 LAST HDL_TAP TRUE
J 2
(-1175 1600);
DISPLAY 0.872340 (-1175 1600);
DISPLAY INVISIBLE (-1175 1600);
FORCEPROP 1 LAST PATH I13
J 2
(-848 1725);
DISPLAY 0.872340 (-848 1725);
PAINT GREEN (-848 1725);
DISPLAY INVISIBLE (-848 1725);
FORCEADD TAP..1
(2925 3025);
FORCEPROP 3 LASTPIN (2875 3025) SIG_NAME UPI_CPU0_CPU1_P1P0_DN<12>
J 0
(2885 3035);
DISPLAY 0.659574 (2885 3035);
PAINT MONO (2885 3035);
DISPLAY INVISIBLE (2885 3035);
FORCEPROP 1 LASTPIN (2875 3025) BN 12
J 0
(2863 3033);
DISPLAY 0.680851 (2863 3033);
PAINT GREEN (2863 3033);
FORCEPROP 2 LAST CDS_LIB standard
J 0
(2925 3025);
PAINT MONO (2925 3025);
DISPLAY INVISIBLE (2925 3025);
FORCEPROP 1 LAST BODY_TYPE PLUMBING
J 0
(2925 3075);
DISPLAY 0.872340 (2925 3075);
PAINT GREEN (2925 3075);
DISPLAY INVISIBLE (2925 3075);
FORCEPROP 1 LAST HDL_TAP TRUE
J 0
(3250 2900);
DISPLAY 0.872340 (3250 2900);
DISPLAY INVISIBLE (3250 2900);
FORCEPROP 1 LAST PATH I130
J 0
(2923 3025);
DISPLAY 0.872340 (2923 3025);
PAINT GREEN (2923 3025);
DISPLAY INVISIBLE (2923 3025);
FORCEADD TAP..1
(2925 3075);
FORCEPROP 3 LASTPIN (2875 3075) SIG_NAME UPI_CPU0_CPU1_P1P0_DN<13>
J 0
(2885 3085);
DISPLAY 0.659574 (2885 3085);
PAINT MONO (2885 3085);
DISPLAY INVISIBLE (2885 3085);
FORCEPROP 1 LASTPIN (2875 3075) BN 13
J 0
(2863 3083);
DISPLAY 0.680851 (2863 3083);
PAINT GREEN (2863 3083);
FORCEPROP 2 LAST CDS_LIB standard
J 0
(2925 3075);
PAINT MONO (2925 3075);
DISPLAY INVISIBLE (2925 3075);
FORCEPROP 1 LAST BODY_TYPE PLUMBING
J 0
(2925 3125);
DISPLAY 0.872340 (2925 3125);
PAINT GREEN (2925 3125);
DISPLAY INVISIBLE (2925 3125);
FORCEPROP 1 LAST HDL_TAP TRUE
J 0
(3250 2950);
DISPLAY 0.872340 (3250 2950);
DISPLAY INVISIBLE (3250 2950);
FORCEPROP 1 LAST PATH I131
J 0
(2923 3075);
DISPLAY 0.872340 (2923 3075);
PAINT GREEN (2923 3075);
DISPLAY INVISIBLE (2923 3075);
FORCEADD TAP..1
(2925 3175);
FORCEPROP 3 LASTPIN (2875 3175) SIG_NAME UPI_CPU0_CPU1_P1P0_DN<15>
J 0
(2885 3185);
DISPLAY 0.659574 (2885 3185);
PAINT MONO (2885 3185);
DISPLAY INVISIBLE (2885 3185);
FORCEPROP 1 LASTPIN (2875 3175) BN 15
J 0
(2863 3183);
DISPLAY 0.680851 (2863 3183);
PAINT GREEN (2863 3183);
FORCEPROP 2 LAST CDS_LIB standard
J 0
(2925 3175);
PAINT MONO (2925 3175);
DISPLAY INVISIBLE (2925 3175);
FORCEPROP 1 LAST BODY_TYPE PLUMBING
J 0
(2925 3225);
DISPLAY 0.872340 (2925 3225);
PAINT GREEN (2925 3225);
DISPLAY INVISIBLE (2925 3225);
FORCEPROP 1 LAST HDL_TAP TRUE
J 0
(3250 3050);
DISPLAY 0.872340 (3250 3050);
DISPLAY INVISIBLE (3250 3050);
FORCEPROP 1 LAST PATH I132
J 0
(2923 3175);
DISPLAY 0.872340 (2923 3175);
PAINT GREEN (2923 3175);
DISPLAY INVISIBLE (2923 3175);
FORCEADD TAP..1
(2925 3225);
FORCEPROP 3 LASTPIN (2875 3225) SIG_NAME UPI_CPU0_CPU1_P1P0_DN<16>
J 0
(2885 3235);
DISPLAY 0.659574 (2885 3235);
PAINT MONO (2885 3235);
DISPLAY INVISIBLE (2885 3235);
FORCEPROP 1 LASTPIN (2875 3225) BN 16
J 0
(2863 3233);
DISPLAY 0.680851 (2863 3233);
PAINT GREEN (2863 3233);
FORCEPROP 2 LAST CDS_LIB standard
J 0
(2925 3225);
PAINT MONO (2925 3225);
DISPLAY INVISIBLE (2925 3225);
FORCEPROP 1 LAST BODY_TYPE PLUMBING
J 0
(2925 3275);
DISPLAY 0.872340 (2925 3275);
PAINT GREEN (2925 3275);
DISPLAY INVISIBLE (2925 3275);
FORCEPROP 1 LAST HDL_TAP TRUE
J 0
(3250 3100);
DISPLAY 0.872340 (3250 3100);
DISPLAY INVISIBLE (3250 3100);
FORCEPROP 1 LAST PATH I133
J 0
(2923 3225);
DISPLAY 0.872340 (2923 3225);
PAINT GREEN (2923 3225);
DISPLAY INVISIBLE (2923 3225);
FORCEADD TAP..1
(2925 3275);
FORCEPROP 3 LASTPIN (2875 3275) SIG_NAME UPI_CPU0_CPU1_P1P0_DN<17>
J 0
(2885 3285);
DISPLAY 0.659574 (2885 3285);
PAINT MONO (2885 3285);
DISPLAY INVISIBLE (2885 3285);
FORCEPROP 1 LASTPIN (2875 3275) BN 17
J 0
(2863 3283);
DISPLAY 0.680851 (2863 3283);
PAINT GREEN (2863 3283);
FORCEPROP 2 LAST CDS_LIB standard
J 0
(2925 3275);
DISPLAY INVISIBLE (2925 3275);
FORCEPROP 1 LAST BODY_TYPE PLUMBING
J 0
(2925 3325);
DISPLAY 0.872340 (2925 3325);
PAINT GREEN (2925 3325);
DISPLAY INVISIBLE (2925 3325);
FORCEPROP 1 LAST HDL_TAP TRUE
J 0
(3250 3150);
DISPLAY 0.872340 (3250 3150);
DISPLAY INVISIBLE (3250 3150);
FORCEPROP 1 LAST PATH I134
J 0
(2923 3275);
DISPLAY 0.872340 (2923 3275);
PAINT GREEN (2923 3275);
DISPLAY INVISIBLE (2923 3275);
FORCEADD TAP..1
(2925 3375);
FORCEPROP 3 LASTPIN (2875 3375) SIG_NAME UPI_CPU0_CPU1_P1P0_DN<19>
J 0
(2885 3385);
DISPLAY 0.659574 (2885 3385);
PAINT MONO (2885 3385);
DISPLAY INVISIBLE (2885 3385);
FORCEPROP 1 LASTPIN (2875 3375) BN 19
J 0
(2863 3383);
DISPLAY 0.680851 (2863 3383);
PAINT GREEN (2863 3383);
FORCEPROP 2 LAST CDS_LIB standard
J 0
(2925 3375);
DISPLAY INVISIBLE (2925 3375);
FORCEPROP 1 LAST BODY_TYPE PLUMBING
J 0
(2925 3425);
DISPLAY 0.872340 (2925 3425);
PAINT GREEN (2925 3425);
DISPLAY INVISIBLE (2925 3425);
FORCEPROP 1 LAST HDL_TAP TRUE
J 0
(3250 3250);
DISPLAY 0.872340 (3250 3250);
DISPLAY INVISIBLE (3250 3250);
FORCEPROP 1 LAST PATH I135
J 0
(2923 3375);
DISPLAY 0.872340 (2923 3375);
PAINT GREEN (2923 3375);
DISPLAY INVISIBLE (2923 3375);
FORCEADD OFFPAGE..2
(4075 2400);
FORCEPROP 2 LAST $XR0 63 
J 0
(4264 2400);
DISPLAY 0.638298 (4264 2400);
PAINT MONO (4264 2400);
FORCEPROP 2 LAST CDS_LIB standard
J 0
(4075 2400);
PAINT MONO (4075 2400);
DISPLAY INVISIBLE (4075 2400);
FORCEPROP 1 LAST OFFPAGE TRUE
J 0
(4400 2275);
DISPLAY 1.170213 (4400 2275);
PAINT GREEN (4400 2275);
DISPLAY INVISIBLE (4400 2275);
FORCEPROP 1 LAST COMMENT_BODY TRUE
J 0
(4030 2305);
DISPLAY 1.170213 (4030 2305);
PAINT GREEN (4030 2305);
DISPLAY INVISIBLE (4030 2305);
FORCEPROP 2 LAST PATH I136
J 0
(4275 2450);
DISPLAY 1.021277 (4275 2450);
DISPLAY INVISIBLE (4275 2450);
FORCEADD TAP..1
(2925 3575);
FORCEPROP 3 LASTPIN (2875 3575) SIG_NAME UPI_CPU0_CPU1_P1P0_DN<23>
J 0
(2885 3585);
DISPLAY 0.659574 (2885 3585);
PAINT MONO (2885 3585);
DISPLAY INVISIBLE (2885 3585);
FORCEPROP 1 LASTPIN (2875 3575) BN 23
J 0
(2863 3583);
DISPLAY 0.680851 (2863 3583);
PAINT GREEN (2863 3583);
FORCEPROP 2 LAST CDS_LIB standard
J 0
(2925 3575);
DISPLAY INVISIBLE (2925 3575);
FORCEPROP 1 LAST BODY_TYPE PLUMBING
J 0
(2925 3625);
DISPLAY 0.872340 (2925 3625);
PAINT GREEN (2925 3625);
DISPLAY INVISIBLE (2925 3625);
FORCEPROP 1 LAST HDL_TAP TRUE
J 0
(3250 3450);
DISPLAY 0.872340 (3250 3450);
DISPLAY INVISIBLE (3250 3450);
FORCEPROP 1 LAST PATH I137
J 0
(2923 3575);
DISPLAY 0.872340 (2923 3575);
PAINT GREEN (2923 3575);
DISPLAY INVISIBLE (2923 3575);
FORCEADD TAP..1
(2925 3475);
FORCEPROP 3 LASTPIN (2875 3475) SIG_NAME UPI_CPU0_CPU1_P1P0_DN<21>
J 0
(2885 3485);
DISPLAY 0.659574 (2885 3485);
PAINT MONO (2885 3485);
DISPLAY INVISIBLE (2885 3485);
FORCEPROP 1 LASTPIN (2875 3475) BN 21
J 0
(2863 3483);
DISPLAY 0.680851 (2863 3483);
PAINT GREEN (2863 3483);
FORCEPROP 2 LAST CDS_LIB standard
J 0
(2925 3475);
DISPLAY INVISIBLE (2925 3475);
FORCEPROP 1 LAST BODY_TYPE PLUMBING
J 0
(2925 3525);
DISPLAY 0.872340 (2925 3525);
PAINT GREEN (2925 3525);
DISPLAY INVISIBLE (2925 3525);
FORCEPROP 1 LAST HDL_TAP TRUE
J 0
(3250 3350);
DISPLAY 0.872340 (3250 3350);
DISPLAY INVISIBLE (3250 3350);
FORCEPROP 1 LAST PATH I138
J 0
(2923 3475);
DISPLAY 0.872340 (2923 3475);
PAINT GREEN (2923 3475);
DISPLAY INVISIBLE (2923 3475);
FORCEADD TAP..1
(2925 3425);
FORCEPROP 3 LASTPIN (2875 3425) SIG_NAME UPI_CPU0_CPU1_P1P0_DN<20>
J 0
(2885 3435);
DISPLAY 0.659574 (2885 3435);
PAINT MONO (2885 3435);
DISPLAY INVISIBLE (2885 3435);
FORCEPROP 1 LASTPIN (2875 3425) BN 20
J 0
(2863 3433);
DISPLAY 0.680851 (2863 3433);
PAINT GREEN (2863 3433);
FORCEPROP 2 LAST CDS_LIB standard
J 0
(2925 3425);
DISPLAY INVISIBLE (2925 3425);
FORCEPROP 1 LAST BODY_TYPE PLUMBING
J 0
(2925 3475);
DISPLAY 0.872340 (2925 3475);
PAINT GREEN (2925 3475);
DISPLAY INVISIBLE (2925 3475);
FORCEPROP 1 LAST HDL_TAP TRUE
J 0
(3250 3300);
DISPLAY 0.872340 (3250 3300);
DISPLAY INVISIBLE (3250 3300);
FORCEPROP 1 LAST PATH I139
J 0
(2923 3425);
DISPLAY 0.872340 (2923 3425);
PAINT GREEN (2923 3425);
DISPLAY INVISIBLE (2923 3425);
FORCEADD TAP..1
R 2
(-850 1875);
FORCEPROP 3 LASTPIN (-800 1875) SIG_NAME UPI_CPU1_CPU0_P0P1_DN<14>
J 0
(-790 1885);
DISPLAY 0.659574 (-790 1885);
PAINT MONO (-790 1885);
DISPLAY INVISIBLE (-790 1885);
FORCEPROP 1 LASTPIN (-800 1875) BN 14
J 2
(-788 1883);
DISPLAY 0.680851 (-788 1883);
PAINT GREEN (-788 1883);
FORCEPROP 2 LAST CDS_LIB standard
J 0
(-850 1875);
DISPLAY INVISIBLE (-850 1875);
FORCEPROP 1 LAST BODY_TYPE PLUMBING
J 2
(-850 1925);
DISPLAY 0.872340 (-850 1925);
PAINT GREEN (-850 1925);
DISPLAY INVISIBLE (-850 1925);
FORCEPROP 1 LAST HDL_TAP TRUE
J 2
(-1175 1750);
DISPLAY 0.872340 (-1175 1750);
DISPLAY INVISIBLE (-1175 1750);
FORCEPROP 1 LAST PATH I14
J 2
(-848 1875);
DISPLAY 0.872340 (-848 1875);
PAINT GREEN (-848 1875);
DISPLAY INVISIBLE (-848 1875);
FORCEADD TAP..1
(2925 3125);
FORCEPROP 3 LASTPIN (2875 3125) SIG_NAME UPI_CPU0_CPU1_P1P0_DN<14>
J 0
(2885 3135);
DISPLAY 0.659574 (2885 3135);
PAINT MONO (2885 3135);
DISPLAY INVISIBLE (2885 3135);
FORCEPROP 1 LASTPIN (2875 3125) BN 14
J 0
(2863 3133);
DISPLAY 0.680851 (2863 3133);
PAINT GREEN (2863 3133);
FORCEPROP 2 LAST CDS_LIB standard
J 0
(2925 3125);
PAINT MONO (2925 3125);
DISPLAY INVISIBLE (2925 3125);
FORCEPROP 1 LAST BODY_TYPE PLUMBING
J 0
(2925 3175);
DISPLAY 0.872340 (2925 3175);
PAINT GREEN (2925 3175);
DISPLAY INVISIBLE (2925 3175);
FORCEPROP 1 LAST HDL_TAP TRUE
J 0
(3250 3000);
DISPLAY 0.872340 (3250 3000);
DISPLAY INVISIBLE (3250 3000);
FORCEPROP 1 LAST PATH I140
J 0
(2923 3125);
DISPLAY 0.872340 (2923 3125);
PAINT GREEN (2923 3125);
DISPLAY INVISIBLE (2923 3125);
FORCEADD TAP..1
(2725 1875);
FORCEPROP 3 LASTPIN (2675 1875) SIG_NAME UPI_CPU0_CPU1_P1P0_DP<14>
J 0
(2685 1885);
DISPLAY 0.659574 (2685 1885);
PAINT MONO (2685 1885);
DISPLAY INVISIBLE (2685 1885);
FORCEPROP 1 LASTPIN (2675 1875) BN 14
J 0
(2663 1883);
DISPLAY 0.680851 (2663 1883);
PAINT GREEN (2663 1883);
FORCEPROP 2 LAST CDS_LIB standard
J 0
(2725 1875);
PAINT MONO (2725 1875);
DISPLAY INVISIBLE (2725 1875);
FORCEPROP 1 LAST BODY_TYPE PLUMBING
J 0
(2725 1925);
DISPLAY 0.872340 (2725 1925);
PAINT GREEN (2725 1925);
DISPLAY INVISIBLE (2725 1925);
FORCEPROP 1 LAST HDL_TAP TRUE
J 0
(3050 1750);
DISPLAY 0.872340 (3050 1750);
DISPLAY INVISIBLE (3050 1750);
FORCEPROP 1 LAST PATH I141
J 0
(2723 1875);
DISPLAY 0.872340 (2723 1875);
PAINT GREEN (2723 1875);
DISPLAY INVISIBLE (2723 1875);
FORCEADD TAP..1
(2725 2075);
FORCEPROP 3 LASTPIN (2675 2075) SIG_NAME UPI_CPU0_CPU1_P1P0_DP<18>
J 0
(2685 2085);
DISPLAY 0.659574 (2685 2085);
PAINT MONO (2685 2085);
DISPLAY INVISIBLE (2685 2085);
FORCEPROP 1 LASTPIN (2675 2075) BN 18
J 0
(2663 2083);
DISPLAY 0.680851 (2663 2083);
PAINT GREEN (2663 2083);
FORCEPROP 2 LAST CDS_LIB standard
J 0
(2725 2075);
DISPLAY INVISIBLE (2725 2075);
FORCEPROP 1 LAST BODY_TYPE PLUMBING
J 0
(2725 2125);
DISPLAY 0.872340 (2725 2125);
PAINT GREEN (2725 2125);
DISPLAY INVISIBLE (2725 2125);
FORCEPROP 1 LAST HDL_TAP TRUE
J 0
(3050 1950);
DISPLAY 0.872340 (3050 1950);
DISPLAY INVISIBLE (3050 1950);
FORCEPROP 1 LAST PATH I142
J 0
(2723 2075);
DISPLAY 0.872340 (2723 2075);
PAINT GREEN (2723 2075);
DISPLAY INVISIBLE (2723 2075);
FORCEADD TAP..1
(2925 3325);
FORCEPROP 3 LASTPIN (2875 3325) SIG_NAME UPI_CPU0_CPU1_P1P0_DN<18>
J 0
(2885 3335);
DISPLAY 0.659574 (2885 3335);
PAINT MONO (2885 3335);
DISPLAY INVISIBLE (2885 3335);
FORCEPROP 1 LASTPIN (2875 3325) BN 18
J 0
(2863 3333);
DISPLAY 0.680851 (2863 3333);
PAINT GREEN (2863 3333);
FORCEPROP 2 LAST CDS_LIB standard
J 0
(2925 3325);
DISPLAY INVISIBLE (2925 3325);
FORCEPROP 1 LAST BODY_TYPE PLUMBING
J 0
(2925 3375);
DISPLAY 0.872340 (2925 3375);
PAINT GREEN (2925 3375);
DISPLAY INVISIBLE (2925 3375);
FORCEPROP 1 LAST HDL_TAP TRUE
J 0
(3250 3200);
DISPLAY 0.872340 (3250 3200);
DISPLAY INVISIBLE (3250 3200);
FORCEPROP 1 LAST PATH I143
J 0
(2923 3325);
DISPLAY 0.872340 (2923 3325);
PAINT GREEN (2923 3325);
DISPLAY INVISIBLE (2923 3325);
FORCEADD TAP..1
R 2
(-650 1275);
FORCEPROP 3 LASTPIN (-600 1275) SIG_NAME UPI_CPU1_CPU0_P0P1_DP<2>
J 0
(-590 1285);
DISPLAY 0.659574 (-590 1285);
PAINT MONO (-590 1285);
DISPLAY INVISIBLE (-590 1285);
FORCEPROP 1 LASTPIN (-600 1275) BN 2
J 2
(-588 1283);
DISPLAY 0.680851 (-588 1283);
PAINT GREEN (-588 1283);
FORCEPROP 2 LAST CDS_LIB standard
J 0
(-650 1275);
DISPLAY INVISIBLE (-650 1275);
FORCEPROP 1 LAST BODY_TYPE PLUMBING
J 2
(-650 1325);
DISPLAY 0.872340 (-650 1325);
PAINT GREEN (-650 1325);
DISPLAY INVISIBLE (-650 1325);
FORCEPROP 1 LAST HDL_TAP TRUE
J 2
(-975 1150);
DISPLAY 0.872340 (-975 1150);
DISPLAY INVISIBLE (-975 1150);
FORCEPROP 1 LAST PATH I144
J 2
(-648 1275);
DISPLAY 0.872340 (-648 1275);
PAINT GREEN (-648 1275);
DISPLAY INVISIBLE (-648 1275);
FORCEADD TAP..1
R 2
(-850 2525);
FORCEPROP 3 LASTPIN (-800 2525) SIG_NAME UPI_CPU1_CPU0_P0P1_DN<2>
J 0
(-790 2535);
DISPLAY 0.659574 (-790 2535);
PAINT MONO (-790 2535);
DISPLAY INVISIBLE (-790 2535);
FORCEPROP 1 LASTPIN (-800 2525) BN 2
J 2
(-788 2533);
DISPLAY 0.680851 (-788 2533);
PAINT GREEN (-788 2533);
FORCEPROP 2 LAST CDS_LIB standard
J 0
(-850 2525);
DISPLAY INVISIBLE (-850 2525);
FORCEPROP 1 LAST BODY_TYPE PLUMBING
J 2
(-850 2575);
DISPLAY 0.872340 (-850 2575);
PAINT GREEN (-850 2575);
DISPLAY INVISIBLE (-850 2575);
FORCEPROP 1 LAST HDL_TAP TRUE
J 2
(-1175 2400);
DISPLAY 0.872340 (-1175 2400);
DISPLAY INVISIBLE (-1175 2400);
FORCEPROP 1 LAST PATH I145
J 2
(-848 2525);
DISPLAY 0.872340 (-848 2525);
PAINT GREEN (-848 2525);
DISPLAY INVISIBLE (-848 2525);
FORCEADD TAP..1
R 2
(-850 1825);
FORCEPROP 3 LASTPIN (-800 1825) SIG_NAME UPI_CPU1_CPU0_P0P1_DN<13>
J 0
(-790 1835);
DISPLAY 0.659574 (-790 1835);
PAINT MONO (-790 1835);
DISPLAY INVISIBLE (-790 1835);
FORCEPROP 1 LASTPIN (-800 1825) BN 13
J 2
(-788 1833);
DISPLAY 0.680851 (-788 1833);
PAINT GREEN (-788 1833);
FORCEPROP 2 LAST CDS_LIB standard
J 0
(-850 1825);
DISPLAY INVISIBLE (-850 1825);
FORCEPROP 1 LAST BODY_TYPE PLUMBING
J 2
(-850 1875);
DISPLAY 0.872340 (-850 1875);
PAINT GREEN (-850 1875);
DISPLAY INVISIBLE (-850 1875);
FORCEPROP 1 LAST HDL_TAP TRUE
J 2
(-1175 1700);
DISPLAY 0.872340 (-1175 1700);
DISPLAY INVISIBLE (-1175 1700);
FORCEPROP 1 LAST PATH I15
J 2
(-848 1825);
DISPLAY 0.872340 (-848 1825);
PAINT GREEN (-848 1825);
DISPLAY INVISIBLE (-848 1825);
FORCEADD TAP..1
R 2
(-850 1925);
FORCEPROP 3 LASTPIN (-800 1925) SIG_NAME UPI_CPU1_CPU0_P0P1_DN<15>
J 0
(-790 1935);
DISPLAY 0.659574 (-790 1935);
PAINT MONO (-790 1935);
DISPLAY INVISIBLE (-790 1935);
FORCEPROP 1 LASTPIN (-800 1925) BN 15
J 2
(-788 1933);
DISPLAY 0.680851 (-788 1933);
PAINT GREEN (-788 1933);
FORCEPROP 2 LAST CDS_LIB standard
J 0
(-850 1925);
DISPLAY INVISIBLE (-850 1925);
FORCEPROP 1 LAST BODY_TYPE PLUMBING
J 2
(-850 1975);
DISPLAY 0.872340 (-850 1975);
PAINT GREEN (-850 1975);
DISPLAY INVISIBLE (-850 1975);
FORCEPROP 1 LAST HDL_TAP TRUE
J 2
(-1175 1800);
DISPLAY 0.872340 (-1175 1800);
DISPLAY INVISIBLE (-1175 1800);
FORCEPROP 1 LAST PATH I16
J 2
(-848 1925);
DISPLAY 0.872340 (-848 1925);
PAINT GREEN (-848 1925);
DISPLAY INVISIBLE (-848 1925);
FORCEADD OFFPAGE..1
(-1900 2400);
FORCEPROP 2 LAST $XR0 63 
J 0
(-2121 2400);
DISPLAY 0.638298 (-2121 2400);
PAINT MONO (-2121 2400);
FORCEPROP 2 LAST CDS_LIB standard
J 0
(-1900 2400);
PAINT MONO (-1900 2400);
DISPLAY INVISIBLE (-1900 2400);
FORCEPROP 1 LAST OFFPAGE TRUE
J 0
(-1575 2275);
DISPLAY 0.872340 (-1575 2275);
DISPLAY INVISIBLE (-1575 2275);
FORCEPROP 1 LAST COMMENT_BODY TRUE
J 0
(-1775 2300);
DISPLAY 0.872340 (-1775 2300);
PAINT GREEN (-1775 2300);
DISPLAY INVISIBLE (-1775 2300);
FORCEPROP 2 LAST PATH I17
J 0
(-1850 2475);
DISPLAY 1.021277 (-1850 2475);
DISPLAY INVISIBLE (-1850 2475);
FORCEADD OFFPAGE..1
(-1900 3675);
FORCEPROP 2 LAST $XR0 63 
J 0
(-2121 3675);
DISPLAY 0.638298 (-2121 3675);
PAINT MONO (-2121 3675);
FORCEPROP 2 LAST CDS_LIB standard
J 0
(-1900 3675);
PAINT MONO (-1900 3675);
DISPLAY INVISIBLE (-1900 3675);
FORCEPROP 1 LAST OFFPAGE TRUE
J 0
(-1575 3550);
DISPLAY 0.872340 (-1575 3550);
DISPLAY INVISIBLE (-1575 3550);
FORCEPROP 1 LAST COMMENT_BODY TRUE
J 0
(-1775 3575);
DISPLAY 0.872340 (-1775 3575);
PAINT GREEN (-1775 3575);
DISPLAY INVISIBLE (-1775 3575);
FORCEPROP 2 LAST PATH I18
J 0
(-1850 3750);
DISPLAY 1.021277 (-1850 3750);
DISPLAY INVISIBLE (-1850 3750);
FORCEADD TAP..1
R 2
(-850 1975);
FORCEPROP 3 LASTPIN (-800 1975) SIG_NAME UPI_CPU1_CPU0_P0P1_DN<16>
J 0
(-790 1985);
DISPLAY 0.659574 (-790 1985);
PAINT MONO (-790 1985);
DISPLAY INVISIBLE (-790 1985);
FORCEPROP 1 LASTPIN (-800 1975) BN 16
J 2
(-788 1983);
DISPLAY 0.680851 (-788 1983);
PAINT GREEN (-788 1983);
FORCEPROP 2 LAST CDS_LIB standard
J 0
(-850 1975);
PAINT MONO (-850 1975);
DISPLAY INVISIBLE (-850 1975);
FORCEPROP 1 LAST BODY_TYPE PLUMBING
J 2
(-850 2025);
DISPLAY 0.872340 (-850 2025);
PAINT GREEN (-850 2025);
DISPLAY INVISIBLE (-850 2025);
FORCEPROP 1 LAST HDL_TAP TRUE
J 2
(-1175 1850);
DISPLAY 0.872340 (-1175 1850);
DISPLAY INVISIBLE (-1175 1850);
FORCEPROP 1 LAST PATH I19
J 2
(-848 1975);
DISPLAY 0.872340 (-848 1975);
PAINT GREEN (-848 1975);
DISPLAY INVISIBLE (-848 1975);
FORCEADD TAP..1
R 2
(-850 1225);
FORCEPROP 3 LASTPIN (-800 1225) SIG_NAME UPI_CPU1_CPU0_P0P1_DN<1>
J 0
(-790 1235);
DISPLAY 0.659574 (-790 1235);
PAINT MONO (-790 1235);
DISPLAY INVISIBLE (-790 1235);
FORCEPROP 1 LASTPIN (-800 1225) BN 1
J 2
(-788 1233);
DISPLAY 0.680851 (-788 1233);
PAINT GREEN (-788 1233);
FORCEPROP 2 LAST CDS_LIB standard
J 0
(-850 1225);
DISPLAY INVISIBLE (-850 1225);
FORCEPROP 1 LAST BODY_TYPE PLUMBING
J 2
(-850 1275);
DISPLAY 0.872340 (-850 1275);
PAINT GREEN (-850 1275);
DISPLAY INVISIBLE (-850 1275);
FORCEPROP 1 LAST HDL_TAP TRUE
J 2
(-1175 1100);
DISPLAY 0.872340 (-1175 1100);
DISPLAY INVISIBLE (-1175 1100);
FORCEPROP 1 LAST PATH I2
J 2
(-848 1225);
DISPLAY 0.872340 (-848 1225);
PAINT GREEN (-848 1225);
DISPLAY INVISIBLE (-848 1225);
FORCEADD TAP..1
R 2
(-650 2025);
FORCEPROP 3 LASTPIN (-600 2025) SIG_NAME UPI_CPU1_CPU0_P0P1_DP<17>
J 0
(-590 2035);
DISPLAY 0.659574 (-590 2035);
PAINT MONO (-590 2035);
DISPLAY INVISIBLE (-590 2035);
FORCEPROP 1 LASTPIN (-600 2025) BN 17
J 2
(-588 2033);
DISPLAY 0.680851 (-588 2033);
PAINT GREEN (-588 2033);
FORCEPROP 2 LAST CDS_LIB standard
J 0
(-650 2025);
PAINT MONO (-650 2025);
DISPLAY INVISIBLE (-650 2025);
FORCEPROP 1 LAST BODY_TYPE PLUMBING
J 2
(-650 2075);
DISPLAY 0.872340 (-650 2075);
PAINT GREEN (-650 2075);
DISPLAY INVISIBLE (-650 2075);
FORCEPROP 1 LAST HDL_TAP TRUE
J 2
(-975 1900);
DISPLAY 0.872340 (-975 1900);
DISPLAY INVISIBLE (-975 1900);
FORCEPROP 1 LAST PATH I20
J 2
(-648 2025);
DISPLAY 0.872340 (-648 2025);
PAINT GREEN (-648 2025);
DISPLAY INVISIBLE (-648 2025);
FORCEADD TAP..1
R 2
(-650 2175);
FORCEPROP 3 LASTPIN (-600 2175) SIG_NAME UPI_CPU1_CPU0_P0P1_DP<20>
J 0
(-590 2185);
DISPLAY 0.659574 (-590 2185);
PAINT MONO (-590 2185);
DISPLAY INVISIBLE (-590 2185);
FORCEPROP 1 LASTPIN (-600 2175) BN 20
J 2
(-588 2183);
DISPLAY 0.680851 (-588 2183);
PAINT GREEN (-588 2183);
FORCEPROP 2 LAST CDS_LIB standard
J 0
(-650 2175);
PAINT MONO (-650 2175);
DISPLAY INVISIBLE (-650 2175);
FORCEPROP 1 LAST BODY_TYPE PLUMBING
J 2
(-650 2225);
DISPLAY 0.872340 (-650 2225);
PAINT GREEN (-650 2225);
DISPLAY INVISIBLE (-650 2225);
FORCEPROP 1 LAST HDL_TAP TRUE
J 2
(-975 2050);
DISPLAY 0.872340 (-975 2050);
DISPLAY INVISIBLE (-975 2050);
FORCEPROP 1 LAST PATH I22
J 2
(-648 2175);
DISPLAY 0.872340 (-648 2175);
PAINT GREEN (-648 2175);
DISPLAY INVISIBLE (-648 2175);
FORCEADD TAP..1
R 2
(-850 2225);
FORCEPROP 3 LASTPIN (-800 2225) SIG_NAME UPI_CPU1_CPU0_P0P1_DN<21>
J 0
(-790 2235);
DISPLAY 0.659574 (-790 2235);
PAINT MONO (-790 2235);
DISPLAY INVISIBLE (-790 2235);
FORCEPROP 1 LASTPIN (-800 2225) BN 21
J 2
(-788 2233);
DISPLAY 0.680851 (-788 2233);
PAINT GREEN (-788 2233);
FORCEPROP 2 LAST CDS_LIB standard
J 0
(-850 2225);
PAINT MONO (-850 2225);
DISPLAY INVISIBLE (-850 2225);
FORCEPROP 1 LAST BODY_TYPE PLUMBING
J 2
(-850 2275);
DISPLAY 0.872340 (-850 2275);
PAINT GREEN (-850 2275);
DISPLAY INVISIBLE (-850 2275);
FORCEPROP 1 LAST HDL_TAP TRUE
J 2
(-1175 2100);
DISPLAY 0.872340 (-1175 2100);
DISPLAY INVISIBLE (-1175 2100);
FORCEPROP 1 LAST PATH I24
J 2
(-848 2225);
DISPLAY 0.872340 (-848 2225);
PAINT GREEN (-848 2225);
DISPLAY INVISIBLE (-848 2225);
FORCEADD TAP..1
R 2
(-650 2275);
FORCEPROP 3 LASTPIN (-600 2275) SIG_NAME UPI_CPU1_CPU0_P0P1_DP<22>
J 0
(-590 2285);
DISPLAY 0.659574 (-590 2285);
PAINT MONO (-590 2285);
DISPLAY INVISIBLE (-590 2285);
FORCEPROP 1 LASTPIN (-600 2275) BN 22
J 2
(-588 2283);
DISPLAY 0.680851 (-588 2283);
PAINT GREEN (-588 2283);
FORCEPROP 2 LAST CDS_LIB standard
J 0
(-650 2275);
PAINT MONO (-650 2275);
DISPLAY INVISIBLE (-650 2275);
FORCEPROP 1 LAST BODY_TYPE PLUMBING
J 2
(-650 2325);
DISPLAY 0.872340 (-650 2325);
PAINT GREEN (-650 2325);
DISPLAY INVISIBLE (-650 2325);
FORCEPROP 1 LAST HDL_TAP TRUE
J 2
(-975 2150);
DISPLAY 0.872340 (-975 2150);
DISPLAY INVISIBLE (-975 2150);
FORCEPROP 1 LAST PATH I25
J 2
(-648 2275);
DISPLAY 0.872340 (-648 2275);
PAINT GREEN (-648 2275);
DISPLAY INVISIBLE (-648 2275);
FORCEADD TAP..1
R 2
(-650 2425);
FORCEPROP 3 LASTPIN (-600 2425) SIG_NAME UPI_CPU1_CPU0_P0P1_DP<0>
J 0
(-590 2435);
DISPLAY 0.659574 (-590 2435);
PAINT MONO (-590 2435);
DISPLAY INVISIBLE (-590 2435);
FORCEPROP 1 LASTPIN (-600 2425) BN 0
J 2
(-588 2433);
DISPLAY 0.680851 (-588 2433);
PAINT GREEN (-588 2433);
FORCEPROP 2 LAST CDS_LIB standard
J 0
(-650 2425);
DISPLAY INVISIBLE (-650 2425);
FORCEPROP 1 LAST BODY_TYPE PLUMBING
J 2
(-650 2475);
DISPLAY 0.872340 (-650 2475);
PAINT GREEN (-650 2475);
DISPLAY INVISIBLE (-650 2475);
FORCEPROP 1 LAST HDL_TAP TRUE
J 2
(-975 2300);
DISPLAY 0.872340 (-975 2300);
DISPLAY INVISIBLE (-975 2300);
FORCEPROP 1 LAST PATH I27
J 2
(-648 2425);
DISPLAY 0.872340 (-648 2425);
PAINT GREEN (-648 2425);
DISPLAY INVISIBLE (-648 2425);
FORCEADD TAP..1
R 2
(-650 2475);
FORCEPROP 3 LASTPIN (-600 2475) SIG_NAME UPI_CPU1_CPU0_P0P1_DP<1>
J 0
(-590 2485);
DISPLAY 0.659574 (-590 2485);
PAINT MONO (-590 2485);
DISPLAY INVISIBLE (-590 2485);
FORCEPROP 1 LASTPIN (-600 2475) BN 1
J 2
(-588 2483);
DISPLAY 0.680851 (-588 2483);
PAINT GREEN (-588 2483);
FORCEPROP 2 LAST CDS_LIB standard
J 0
(-650 2475);
DISPLAY INVISIBLE (-650 2475);
FORCEPROP 1 LAST BODY_TYPE PLUMBING
J 2
(-650 2525);
DISPLAY 0.872340 (-650 2525);
PAINT GREEN (-650 2525);
DISPLAY INVISIBLE (-650 2525);
FORCEPROP 1 LAST HDL_TAP TRUE
J 2
(-975 2350);
DISPLAY 0.872340 (-975 2350);
DISPLAY INVISIBLE (-975 2350);
FORCEPROP 1 LAST PATH I29
J 2
(-648 2475);
DISPLAY 0.872340 (-648 2475);
PAINT GREEN (-648 2475);
DISPLAY INVISIBLE (-648 2475);
FORCEADD TAP..1
R 2
(-650 2575);
FORCEPROP 3 LASTPIN (-600 2575) SIG_NAME UPI_CPU1_CPU0_P0P1_DP<3>
J 0
(-590 2585);
DISPLAY 0.659574 (-590 2585);
PAINT MONO (-590 2585);
DISPLAY INVISIBLE (-590 2585);
FORCEPROP 1 LASTPIN (-600 2575) BN 3
J 2
(-588 2583);
DISPLAY 0.680851 (-588 2583);
PAINT GREEN (-588 2583);
FORCEPROP 2 LAST CDS_LIB standard
J 0
(-650 2575);
DISPLAY INVISIBLE (-650 2575);
FORCEPROP 1 LAST BODY_TYPE PLUMBING
J 2
(-650 2625);
DISPLAY 0.872340 (-650 2625);
PAINT GREEN (-650 2625);
DISPLAY INVISIBLE (-650 2625);
FORCEPROP 1 LAST HDL_TAP TRUE
J 2
(-975 2450);
DISPLAY 0.872340 (-975 2450);
DISPLAY INVISIBLE (-975 2450);
FORCEPROP 1 LAST PATH I30
J 2
(-648 2575);
DISPLAY 0.872340 (-648 2575);
PAINT GREEN (-648 2575);
DISPLAY INVISIBLE (-648 2575);
FORCEADD TAP..1
R 2
(-650 2675);
FORCEPROP 3 LASTPIN (-600 2675) SIG_NAME UPI_CPU1_CPU0_P0P1_DP<5>
J 0
(-590 2685);
DISPLAY 0.659574 (-590 2685);
PAINT MONO (-590 2685);
DISPLAY INVISIBLE (-590 2685);
FORCEPROP 1 LASTPIN (-600 2675) BN 5
J 2
(-588 2683);
DISPLAY 0.680851 (-588 2683);
PAINT GREEN (-588 2683);
FORCEPROP 2 LAST CDS_LIB standard
J 0
(-650 2675);
DISPLAY INVISIBLE (-650 2675);
FORCEPROP 1 LAST BODY_TYPE PLUMBING
J 2
(-650 2725);
DISPLAY 0.872340 (-650 2725);
PAINT GREEN (-650 2725);
DISPLAY INVISIBLE (-650 2725);
FORCEPROP 1 LAST HDL_TAP TRUE
J 2
(-975 2550);
DISPLAY 0.872340 (-975 2550);
DISPLAY INVISIBLE (-975 2550);
FORCEPROP 1 LAST PATH I31
J 2
(-648 2675);
DISPLAY 0.872340 (-648 2675);
PAINT GREEN (-648 2675);
DISPLAY INVISIBLE (-648 2675);
FORCEADD TAP..1
R 2
(-650 2625);
FORCEPROP 3 LASTPIN (-600 2625) SIG_NAME UPI_CPU1_CPU0_P0P1_DP<4>
J 0
(-590 2635);
DISPLAY 0.659574 (-590 2635);
PAINT MONO (-590 2635);
DISPLAY INVISIBLE (-590 2635);
FORCEPROP 1 LASTPIN (-600 2625) BN 4
J 2
(-588 2633);
DISPLAY 0.680851 (-588 2633);
PAINT GREEN (-588 2633);
FORCEPROP 2 LAST CDS_LIB standard
J 0
(-650 2625);
DISPLAY INVISIBLE (-650 2625);
FORCEPROP 1 LAST BODY_TYPE PLUMBING
J 2
(-650 2675);
DISPLAY 0.872340 (-650 2675);
PAINT GREEN (-650 2675);
DISPLAY INVISIBLE (-650 2675);
FORCEPROP 1 LAST HDL_TAP TRUE
J 2
(-975 2500);
DISPLAY 0.872340 (-975 2500);
DISPLAY INVISIBLE (-975 2500);
FORCEPROP 1 LAST PATH I32
J 2
(-648 2625);
DISPLAY 0.872340 (-648 2625);
PAINT GREEN (-648 2625);
DISPLAY INVISIBLE (-648 2625);
FORCEADD TAP..1
R 2
(-650 2725);
FORCEPROP 3 LASTPIN (-600 2725) SIG_NAME UPI_CPU1_CPU0_P0P1_DP<6>
J 0
(-590 2735);
DISPLAY 0.659574 (-590 2735);
PAINT MONO (-590 2735);
DISPLAY INVISIBLE (-590 2735);
FORCEPROP 1 LASTPIN (-600 2725) BN 6
J 2
(-588 2733);
DISPLAY 0.680851 (-588 2733);
PAINT GREEN (-588 2733);
FORCEPROP 2 LAST CDS_LIB standard
J 0
(-650 2725);
DISPLAY INVISIBLE (-650 2725);
FORCEPROP 1 LAST BODY_TYPE PLUMBING
J 2
(-650 2775);
DISPLAY 0.872340 (-650 2775);
PAINT GREEN (-650 2775);
DISPLAY INVISIBLE (-650 2775);
FORCEPROP 1 LAST HDL_TAP TRUE
J 2
(-975 2600);
DISPLAY 0.872340 (-975 2600);
DISPLAY INVISIBLE (-975 2600);
FORCEPROP 1 LAST PATH I33
J 2
(-648 2725);
DISPLAY 0.872340 (-648 2725);
PAINT GREEN (-648 2725);
DISPLAY INVISIBLE (-648 2725);
FORCEADD TAP..1
R 2
(-650 2775);
FORCEPROP 3 LASTPIN (-600 2775) SIG_NAME UPI_CPU1_CPU0_P0P1_DP<7>
J 0
(-590 2785);
DISPLAY 0.659574 (-590 2785);
PAINT MONO (-590 2785);
DISPLAY INVISIBLE (-590 2785);
FORCEPROP 1 LASTPIN (-600 2775) BN 7
J 2
(-588 2783);
DISPLAY 0.680851 (-588 2783);
PAINT GREEN (-588 2783);
FORCEPROP 2 LAST CDS_LIB standard
J 0
(-650 2775);
DISPLAY INVISIBLE (-650 2775);
FORCEPROP 1 LAST BODY_TYPE PLUMBING
J 2
(-650 2825);
DISPLAY 0.872340 (-650 2825);
PAINT GREEN (-650 2825);
DISPLAY INVISIBLE (-650 2825);
FORCEPROP 1 LAST HDL_TAP TRUE
J 2
(-975 2650);
DISPLAY 0.872340 (-975 2650);
DISPLAY INVISIBLE (-975 2650);
FORCEPROP 1 LAST PATH I34
J 2
(-648 2775);
DISPLAY 0.872340 (-648 2775);
PAINT GREEN (-648 2775);
DISPLAY INVISIBLE (-648 2775);
FORCEADD TAP..1
R 2
(-650 2825);
FORCEPROP 3 LASTPIN (-600 2825) SIG_NAME UPI_CPU1_CPU0_P0P1_DP<8>
J 0
(-590 2835);
DISPLAY 0.659574 (-590 2835);
PAINT MONO (-590 2835);
DISPLAY INVISIBLE (-590 2835);
FORCEPROP 1 LASTPIN (-600 2825) BN 8
J 2
(-588 2833);
DISPLAY 0.680851 (-588 2833);
PAINT GREEN (-588 2833);
FORCEPROP 2 LAST CDS_LIB standard
J 0
(-650 2825);
DISPLAY INVISIBLE (-650 2825);
FORCEPROP 1 LAST BODY_TYPE PLUMBING
J 2
(-650 2875);
DISPLAY 0.872340 (-650 2875);
PAINT GREEN (-650 2875);
DISPLAY INVISIBLE (-650 2875);
FORCEPROP 1 LAST HDL_TAP TRUE
J 2
(-975 2700);
DISPLAY 0.872340 (-975 2700);
DISPLAY INVISIBLE (-975 2700);
FORCEPROP 1 LAST PATH I35
J 2
(-648 2825);
DISPLAY 0.872340 (-648 2825);
PAINT GREEN (-648 2825);
DISPLAY INVISIBLE (-648 2825);
FORCEADD TAP..1
R 2
(-650 2925);
FORCEPROP 3 LASTPIN (-600 2925) SIG_NAME UPI_CPU1_CPU0_P0P1_DP<10>
J 0
(-590 2935);
DISPLAY 0.659574 (-590 2935);
PAINT MONO (-590 2935);
DISPLAY INVISIBLE (-590 2935);
FORCEPROP 1 LASTPIN (-600 2925) BN 10
J 2
(-588 2933);
DISPLAY 0.680851 (-588 2933);
PAINT GREEN (-588 2933);
FORCEPROP 2 LAST CDS_LIB standard
J 0
(-650 2925);
DISPLAY INVISIBLE (-650 2925);
FORCEPROP 1 LAST BODY_TYPE PLUMBING
J 2
(-650 2975);
DISPLAY 0.872340 (-650 2975);
PAINT GREEN (-650 2975);
DISPLAY INVISIBLE (-650 2975);
FORCEPROP 1 LAST HDL_TAP TRUE
J 2
(-975 2800);
DISPLAY 0.872340 (-975 2800);
DISPLAY INVISIBLE (-975 2800);
FORCEPROP 1 LAST PATH I36
J 2
(-648 2925);
DISPLAY 0.872340 (-648 2925);
PAINT GREEN (-648 2925);
DISPLAY INVISIBLE (-648 2925);
FORCEADD TAP..1
R 2
(-650 2875);
FORCEPROP 3 LASTPIN (-600 2875) SIG_NAME UPI_CPU1_CPU0_P0P1_DP<9>
J 0
(-590 2885);
DISPLAY 0.659574 (-590 2885);
PAINT MONO (-590 2885);
DISPLAY INVISIBLE (-590 2885);
FORCEPROP 1 LASTPIN (-600 2875) BN 9
J 2
(-588 2883);
DISPLAY 0.680851 (-588 2883);
PAINT GREEN (-588 2883);
FORCEPROP 2 LAST CDS_LIB standard
J 0
(-650 2875);
DISPLAY INVISIBLE (-650 2875);
FORCEPROP 1 LAST BODY_TYPE PLUMBING
J 2
(-650 2925);
DISPLAY 0.872340 (-650 2925);
PAINT GREEN (-650 2925);
DISPLAY INVISIBLE (-650 2925);
FORCEPROP 1 LAST HDL_TAP TRUE
J 2
(-975 2750);
DISPLAY 0.872340 (-975 2750);
DISPLAY INVISIBLE (-975 2750);
FORCEPROP 1 LAST PATH I37
J 2
(-648 2875);
DISPLAY 0.872340 (-648 2875);
PAINT GREEN (-648 2875);
DISPLAY INVISIBLE (-648 2875);
FORCEADD TAP..1
R 2
(-650 2975);
FORCEPROP 3 LASTPIN (-600 2975) SIG_NAME UPI_CPU1_CPU0_P0P1_DP<11>
J 0
(-590 2985);
DISPLAY 0.659574 (-590 2985);
PAINT MONO (-590 2985);
DISPLAY INVISIBLE (-590 2985);
FORCEPROP 1 LASTPIN (-600 2975) BN 11
J 2
(-588 2983);
DISPLAY 0.680851 (-588 2983);
PAINT GREEN (-588 2983);
FORCEPROP 2 LAST CDS_LIB standard
J 0
(-650 2975);
DISPLAY INVISIBLE (-650 2975);
FORCEPROP 1 LAST BODY_TYPE PLUMBING
J 2
(-650 3025);
DISPLAY 0.872340 (-650 3025);
PAINT GREEN (-650 3025);
DISPLAY INVISIBLE (-650 3025);
FORCEPROP 1 LAST HDL_TAP TRUE
J 2
(-975 2850);
DISPLAY 0.872340 (-975 2850);
DISPLAY INVISIBLE (-975 2850);
FORCEPROP 1 LAST PATH I38
J 2
(-648 2975);
DISPLAY 0.872340 (-648 2975);
PAINT GREEN (-648 2975);
DISPLAY INVISIBLE (-648 2975);
FORCEADD TAP..1
R 2
(-850 1325);
FORCEPROP 3 LASTPIN (-800 1325) SIG_NAME UPI_CPU1_CPU0_P0P1_DN<3>
J 0
(-790 1335);
DISPLAY 0.659574 (-790 1335);
PAINT MONO (-790 1335);
DISPLAY INVISIBLE (-790 1335);
FORCEPROP 1 LASTPIN (-800 1325) BN 3
J 2
(-788 1333);
DISPLAY 0.680851 (-788 1333);
PAINT GREEN (-788 1333);
FORCEPROP 2 LAST CDS_LIB standard
J 0
(-850 1325);
DISPLAY INVISIBLE (-850 1325);
FORCEPROP 1 LAST BODY_TYPE PLUMBING
J 2
(-850 1375);
DISPLAY 0.872340 (-850 1375);
PAINT GREEN (-850 1375);
DISPLAY INVISIBLE (-850 1375);
FORCEPROP 1 LAST HDL_TAP TRUE
J 2
(-1175 1200);
DISPLAY 0.872340 (-1175 1200);
DISPLAY INVISIBLE (-1175 1200);
FORCEPROP 1 LAST PATH I4
J 2
(-848 1325);
DISPLAY 0.872340 (-848 1325);
PAINT GREEN (-848 1325);
DISPLAY INVISIBLE (-848 1325);
FORCEADD TAP..1
R 2
(-650 3075);
FORCEPROP 3 LASTPIN (-600 3075) SIG_NAME UPI_CPU1_CPU0_P0P1_DP<13>
J 0
(-590 3085);
DISPLAY 0.659574 (-590 3085);
PAINT MONO (-590 3085);
DISPLAY INVISIBLE (-590 3085);
FORCEPROP 1 LASTPIN (-600 3075) BN 13
J 2
(-588 3083);
DISPLAY 0.680851 (-588 3083);
PAINT GREEN (-588 3083);
FORCEPROP 2 LAST CDS_LIB standard
J 0
(-650 3075);
DISPLAY INVISIBLE (-650 3075);
FORCEPROP 1 LAST BODY_TYPE PLUMBING
J 2
(-650 3125);
DISPLAY 0.872340 (-650 3125);
PAINT GREEN (-650 3125);
DISPLAY INVISIBLE (-650 3125);
FORCEPROP 1 LAST HDL_TAP TRUE
J 2
(-975 2950);
DISPLAY 0.872340 (-975 2950);
DISPLAY INVISIBLE (-975 2950);
FORCEPROP 1 LAST PATH I40
J 2
(-648 3075);
DISPLAY 0.872340 (-648 3075);
PAINT GREEN (-648 3075);
DISPLAY INVISIBLE (-648 3075);
FORCEADD TAP..1
R 2
(-650 3125);
FORCEPROP 3 LASTPIN (-600 3125) SIG_NAME UPI_CPU1_CPU0_P0P1_DP<14>
J 0
(-590 3135);
DISPLAY 0.659574 (-590 3135);
PAINT MONO (-590 3135);
DISPLAY INVISIBLE (-590 3135);
FORCEPROP 1 LASTPIN (-600 3125) BN 14
J 2
(-588 3133);
DISPLAY 0.680851 (-588 3133);
PAINT GREEN (-588 3133);
FORCEPROP 2 LAST CDS_LIB standard
J 0
(-650 3125);
DISPLAY INVISIBLE (-650 3125);
FORCEPROP 1 LAST BODY_TYPE PLUMBING
J 2
(-650 3175);
DISPLAY 0.872340 (-650 3175);
PAINT GREEN (-650 3175);
DISPLAY INVISIBLE (-650 3175);
FORCEPROP 1 LAST HDL_TAP TRUE
J 2
(-975 3000);
DISPLAY 0.872340 (-975 3000);
DISPLAY INVISIBLE (-975 3000);
FORCEPROP 1 LAST PATH I41
J 2
(-648 3125);
DISPLAY 0.872340 (-648 3125);
PAINT GREEN (-648 3125);
DISPLAY INVISIBLE (-648 3125);
FORCEADD TAP..1
R 2
(-650 3175);
FORCEPROP 3 LASTPIN (-600 3175) SIG_NAME UPI_CPU1_CPU0_P0P1_DP<15>
J 0
(-590 3185);
DISPLAY 0.659574 (-590 3185);
PAINT MONO (-590 3185);
DISPLAY INVISIBLE (-590 3185);
FORCEPROP 1 LASTPIN (-600 3175) BN 15
J 2
(-588 3183);
DISPLAY 0.680851 (-588 3183);
PAINT GREEN (-588 3183);
FORCEPROP 2 LAST CDS_LIB standard
J 0
(-650 3175);
DISPLAY INVISIBLE (-650 3175);
FORCEPROP 1 LAST BODY_TYPE PLUMBING
J 2
(-650 3225);
DISPLAY 0.872340 (-650 3225);
PAINT GREEN (-650 3225);
DISPLAY INVISIBLE (-650 3225);
FORCEPROP 1 LAST HDL_TAP TRUE
J 2
(-975 3050);
DISPLAY 0.872340 (-975 3050);
DISPLAY INVISIBLE (-975 3050);
FORCEPROP 1 LAST PATH I42
J 2
(-648 3175);
DISPLAY 0.872340 (-648 3175);
PAINT GREEN (-648 3175);
DISPLAY INVISIBLE (-648 3175);
FORCEADD TAP..1
R 2
(-650 3225);
FORCEPROP 3 LASTPIN (-600 3225) SIG_NAME UPI_CPU1_CPU0_P0P1_DP<16>
J 0
(-590 3235);
DISPLAY 0.659574 (-590 3235);
PAINT MONO (-590 3235);
DISPLAY INVISIBLE (-590 3235);
FORCEPROP 1 LASTPIN (-600 3225) BN 16
J 2
(-588 3233);
DISPLAY 0.680851 (-588 3233);
PAINT GREEN (-588 3233);
FORCEPROP 2 LAST CDS_LIB standard
J 0
(-650 3225);
DISPLAY INVISIBLE (-650 3225);
FORCEPROP 1 LAST BODY_TYPE PLUMBING
J 2
(-650 3275);
DISPLAY 0.872340 (-650 3275);
PAINT GREEN (-650 3275);
DISPLAY INVISIBLE (-650 3275);
FORCEPROP 1 LAST HDL_TAP TRUE
J 2
(-975 3100);
DISPLAY 0.872340 (-975 3100);
DISPLAY INVISIBLE (-975 3100);
FORCEPROP 1 LAST PATH I43
J 2
(-648 3225);
DISPLAY 0.872340 (-648 3225);
PAINT GREEN (-648 3225);
DISPLAY INVISIBLE (-648 3225);
FORCEADD TAP..1
R 2
(-650 3325);
FORCEPROP 3 LASTPIN (-600 3325) SIG_NAME UPI_CPU1_CPU0_P0P1_DP<18>
J 0
(-590 3335);
DISPLAY 0.659574 (-590 3335);
PAINT MONO (-590 3335);
DISPLAY INVISIBLE (-590 3335);
FORCEPROP 1 LASTPIN (-600 3325) BN 18
J 2
(-588 3333);
DISPLAY 0.680851 (-588 3333);
PAINT GREEN (-588 3333);
FORCEPROP 2 LAST CDS_LIB standard
J 0
(-650 3325);
DISPLAY INVISIBLE (-650 3325);
FORCEPROP 1 LAST BODY_TYPE PLUMBING
J 2
(-650 3375);
DISPLAY 0.872340 (-650 3375);
PAINT GREEN (-650 3375);
DISPLAY INVISIBLE (-650 3375);
FORCEPROP 1 LAST HDL_TAP TRUE
J 2
(-975 3200);
DISPLAY 0.872340 (-975 3200);
DISPLAY INVISIBLE (-975 3200);
FORCEPROP 1 LAST PATH I44
J 2
(-648 3325);
DISPLAY 0.872340 (-648 3325);
PAINT GREEN (-648 3325);
DISPLAY INVISIBLE (-648 3325);
FORCEADD TAP..1
R 2
(-650 3475);
FORCEPROP 3 LASTPIN (-600 3475) SIG_NAME UPI_CPU1_CPU0_P0P1_DP<21>
J 0
(-590 3485);
DISPLAY 0.659574 (-590 3485);
PAINT MONO (-590 3485);
DISPLAY INVISIBLE (-590 3485);
FORCEPROP 1 LASTPIN (-600 3475) BN 21
J 2
(-588 3483);
DISPLAY 0.680851 (-588 3483);
PAINT GREEN (-588 3483);
FORCEPROP 2 LAST CDS_LIB standard
J 0
(-650 3475);
DISPLAY INVISIBLE (-650 3475);
FORCEPROP 1 LAST BODY_TYPE PLUMBING
J 2
(-650 3525);
DISPLAY 0.872340 (-650 3525);
PAINT GREEN (-650 3525);
DISPLAY INVISIBLE (-650 3525);
FORCEPROP 1 LAST HDL_TAP TRUE
J 2
(-975 3350);
DISPLAY 0.872340 (-975 3350);
DISPLAY INVISIBLE (-975 3350);
FORCEPROP 1 LAST PATH I48
J 2
(-648 3475);
DISPLAY 0.872340 (-648 3475);
PAINT GREEN (-648 3475);
DISPLAY INVISIBLE (-648 3475);
FORCEADD TAP..1
R 2
(-850 1375);
FORCEPROP 3 LASTPIN (-800 1375) SIG_NAME UPI_CPU1_CPU0_P0P1_DN<4>
J 0
(-790 1385);
DISPLAY 0.659574 (-790 1385);
PAINT MONO (-790 1385);
DISPLAY INVISIBLE (-790 1385);
FORCEPROP 1 LASTPIN (-800 1375) BN 4
J 2
(-788 1383);
DISPLAY 0.680851 (-788 1383);
PAINT GREEN (-788 1383);
FORCEPROP 2 LAST CDS_LIB standard
J 0
(-850 1375);
DISPLAY INVISIBLE (-850 1375);
FORCEPROP 1 LAST BODY_TYPE PLUMBING
J 2
(-850 1425);
DISPLAY 0.872340 (-850 1425);
PAINT GREEN (-850 1425);
DISPLAY INVISIBLE (-850 1425);
FORCEPROP 1 LAST HDL_TAP TRUE
J 2
(-1175 1250);
DISPLAY 0.872340 (-1175 1250);
DISPLAY INVISIBLE (-1175 1250);
FORCEPROP 1 LAST PATH I5
J 2
(-848 1375);
DISPLAY 0.872340 (-848 1375);
PAINT GREEN (-848 1375);
DISPLAY INVISIBLE (-848 1375);
FORCEADD TAP..1
(2925 1175);
FORCEPROP 3 LASTPIN (2875 1175) SIG_NAME UPI_CPU0_CPU1_P1P0_DN<0>
J 0
(2885 1185);
DISPLAY 0.659574 (2885 1185);
PAINT MONO (2885 1185);
DISPLAY INVISIBLE (2885 1185);
FORCEPROP 1 LASTPIN (2875 1175) BN 0
J 0
(2863 1183);
DISPLAY 0.680851 (2863 1183);
PAINT GREEN (2863 1183);
FORCEPROP 2 LAST CDS_LIB standard
J 0
(2925 1175);
PAINT MONO (2925 1175);
DISPLAY INVISIBLE (2925 1175);
FORCEPROP 1 LAST BODY_TYPE PLUMBING
J 0
(2925 1225);
DISPLAY 0.872340 (2925 1225);
PAINT GREEN (2925 1225);
DISPLAY INVISIBLE (2925 1225);
FORCEPROP 1 LAST HDL_TAP TRUE
J 0
(3250 1050);
DISPLAY 0.872340 (3250 1050);
DISPLAY INVISIBLE (3250 1050);
FORCEPROP 1 LAST PATH I52
J 0
(2923 1175);
DISPLAY 0.872340 (2923 1175);
PAINT GREEN (2923 1175);
DISPLAY INVISIBLE (2923 1175);
FORCEADD TAP..1
(2925 1225);
FORCEPROP 3 LASTPIN (2875 1225) SIG_NAME UPI_CPU0_CPU1_P1P0_DN<1>
J 0
(2885 1235);
DISPLAY 0.659574 (2885 1235);
PAINT MONO (2885 1235);
DISPLAY INVISIBLE (2885 1235);
FORCEPROP 1 LASTPIN (2875 1225) BN 1
J 0
(2863 1233);
DISPLAY 0.680851 (2863 1233);
PAINT GREEN (2863 1233);
FORCEPROP 2 LAST CDS_LIB standard
J 0
(2925 1225);
PAINT MONO (2925 1225);
DISPLAY INVISIBLE (2925 1225);
FORCEPROP 1 LAST BODY_TYPE PLUMBING
J 0
(2925 1275);
DISPLAY 0.872340 (2925 1275);
PAINT GREEN (2925 1275);
DISPLAY INVISIBLE (2925 1275);
FORCEPROP 1 LAST HDL_TAP TRUE
J 0
(3250 1100);
DISPLAY 0.872340 (3250 1100);
DISPLAY INVISIBLE (3250 1100);
FORCEPROP 1 LAST PATH I53
J 0
(2923 1225);
DISPLAY 0.872340 (2923 1225);
PAINT GREEN (2923 1225);
DISPLAY INVISIBLE (2923 1225);
FORCEADD TAP..1
(2925 1275);
FORCEPROP 3 LASTPIN (2875 1275) SIG_NAME UPI_CPU0_CPU1_P1P0_DN<2>
J 0
(2885 1285);
DISPLAY 0.659574 (2885 1285);
PAINT MONO (2885 1285);
DISPLAY INVISIBLE (2885 1285);
FORCEPROP 1 LASTPIN (2875 1275) BN 2
J 0
(2863 1283);
DISPLAY 0.680851 (2863 1283);
PAINT GREEN (2863 1283);
FORCEPROP 2 LAST CDS_LIB standard
J 0
(2925 1275);
PAINT MONO (2925 1275);
DISPLAY INVISIBLE (2925 1275);
FORCEPROP 1 LAST BODY_TYPE PLUMBING
J 0
(2925 1325);
DISPLAY 0.872340 (2925 1325);
PAINT GREEN (2925 1325);
DISPLAY INVISIBLE (2925 1325);
FORCEPROP 1 LAST HDL_TAP TRUE
J 0
(3250 1150);
DISPLAY 0.872340 (3250 1150);
DISPLAY INVISIBLE (3250 1150);
FORCEPROP 1 LAST PATH I54
J 0
(2923 1275);
DISPLAY 0.872340 (2923 1275);
PAINT GREEN (2923 1275);
DISPLAY INVISIBLE (2923 1275);
FORCEADD TAP..1
(2925 1375);
FORCEPROP 3 LASTPIN (2875 1375) SIG_NAME UPI_CPU0_CPU1_P1P0_DN<4>
J 0
(2885 1385);
DISPLAY 0.659574 (2885 1385);
PAINT MONO (2885 1385);
DISPLAY INVISIBLE (2885 1385);
FORCEPROP 1 LASTPIN (2875 1375) BN 4
J 0
(2863 1383);
DISPLAY 0.680851 (2863 1383);
PAINT GREEN (2863 1383);
FORCEPROP 2 LAST CDS_LIB standard
J 0
(2925 1375);
PAINT MONO (2925 1375);
DISPLAY INVISIBLE (2925 1375);
FORCEPROP 1 LAST BODY_TYPE PLUMBING
J 0
(2925 1425);
DISPLAY 0.872340 (2925 1425);
PAINT GREEN (2925 1425);
DISPLAY INVISIBLE (2925 1425);
FORCEPROP 1 LAST HDL_TAP TRUE
J 0
(3250 1250);
DISPLAY 0.872340 (3250 1250);
DISPLAY INVISIBLE (3250 1250);
FORCEPROP 1 LAST PATH I56
J 0
(2923 1375);
DISPLAY 0.872340 (2923 1375);
PAINT GREEN (2923 1375);
DISPLAY INVISIBLE (2923 1375);
FORCEADD TAP..1
(2925 1475);
FORCEPROP 3 LASTPIN (2875 1475) SIG_NAME UPI_CPU0_CPU1_P1P0_DN<6>
J 0
(2885 1485);
DISPLAY 0.659574 (2885 1485);
PAINT MONO (2885 1485);
DISPLAY INVISIBLE (2885 1485);
FORCEPROP 1 LASTPIN (2875 1475) BN 6
J 0
(2863 1483);
DISPLAY 0.680851 (2863 1483);
PAINT GREEN (2863 1483);
FORCEPROP 2 LAST CDS_LIB standard
J 0
(2925 1475);
PAINT MONO (2925 1475);
DISPLAY INVISIBLE (2925 1475);
FORCEPROP 1 LAST BODY_TYPE PLUMBING
J 0
(2925 1525);
DISPLAY 0.872340 (2925 1525);
PAINT GREEN (2925 1525);
DISPLAY INVISIBLE (2925 1525);
FORCEPROP 1 LAST HDL_TAP TRUE
J 0
(3250 1350);
DISPLAY 0.872340 (3250 1350);
DISPLAY INVISIBLE (3250 1350);
FORCEPROP 1 LAST PATH I58
J 0
(2923 1475);
DISPLAY 0.872340 (2923 1475);
PAINT GREEN (2923 1475);
DISPLAY INVISIBLE (2923 1475);
FORCEADD TAP..1
(2925 1525);
FORCEPROP 3 LASTPIN (2875 1525) SIG_NAME UPI_CPU0_CPU1_P1P0_DN<7>
J 0
(2885 1535);
DISPLAY 0.659574 (2885 1535);
PAINT MONO (2885 1535);
DISPLAY INVISIBLE (2885 1535);
FORCEPROP 1 LASTPIN (2875 1525) BN 7
J 0
(2863 1533);
DISPLAY 0.680851 (2863 1533);
PAINT GREEN (2863 1533);
FORCEPROP 2 LAST CDS_LIB standard
J 0
(2925 1525);
PAINT MONO (2925 1525);
DISPLAY INVISIBLE (2925 1525);
FORCEPROP 1 LAST BODY_TYPE PLUMBING
J 0
(2925 1575);
DISPLAY 0.872340 (2925 1575);
PAINT GREEN (2925 1575);
DISPLAY INVISIBLE (2925 1575);
FORCEPROP 1 LAST HDL_TAP TRUE
J 0
(3250 1400);
DISPLAY 0.872340 (3250 1400);
DISPLAY INVISIBLE (3250 1400);
FORCEPROP 1 LAST PATH I59
J 0
(2923 1525);
DISPLAY 0.872340 (2923 1525);
PAINT GREEN (2923 1525);
DISPLAY INVISIBLE (2923 1525);
FORCEADD TAP..1
R 2
(-850 1425);
FORCEPROP 3 LASTPIN (-800 1425) SIG_NAME UPI_CPU1_CPU0_P0P1_DN<5>
J 0
(-790 1435);
DISPLAY 0.659574 (-790 1435);
PAINT MONO (-790 1435);
DISPLAY INVISIBLE (-790 1435);
FORCEPROP 1 LASTPIN (-800 1425) BN 5
J 2
(-788 1433);
DISPLAY 0.680851 (-788 1433);
PAINT GREEN (-788 1433);
FORCEPROP 2 LAST CDS_LIB standard
J 0
(-850 1425);
DISPLAY INVISIBLE (-850 1425);
FORCEPROP 1 LAST BODY_TYPE PLUMBING
J 2
(-850 1475);
DISPLAY 0.872340 (-850 1475);
PAINT GREEN (-850 1475);
DISPLAY INVISIBLE (-850 1475);
FORCEPROP 1 LAST HDL_TAP TRUE
J 2
(-1175 1300);
DISPLAY 0.872340 (-1175 1300);
DISPLAY INVISIBLE (-1175 1300);
FORCEPROP 1 LAST PATH I6
J 2
(-848 1425);
DISPLAY 0.872340 (-848 1425);
PAINT GREEN (-848 1425);
DISPLAY INVISIBLE (-848 1425);
FORCEADD TAP..1
(2925 1575);
FORCEPROP 3 LASTPIN (2875 1575) SIG_NAME UPI_CPU0_CPU1_P1P0_DN<8>
J 0
(2885 1585);
DISPLAY 0.659574 (2885 1585);
PAINT MONO (2885 1585);
DISPLAY INVISIBLE (2885 1585);
FORCEPROP 1 LASTPIN (2875 1575) BN 8
J 0
(2863 1583);
DISPLAY 0.680851 (2863 1583);
PAINT GREEN (2863 1583);
FORCEPROP 2 LAST CDS_LIB standard
J 0
(2925 1575);
PAINT MONO (2925 1575);
DISPLAY INVISIBLE (2925 1575);
FORCEPROP 1 LAST BODY_TYPE PLUMBING
J 0
(2925 1625);
DISPLAY 0.872340 (2925 1625);
PAINT GREEN (2925 1625);
DISPLAY INVISIBLE (2925 1625);
FORCEPROP 1 LAST HDL_TAP TRUE
J 0
(3250 1450);
DISPLAY 0.872340 (3250 1450);
DISPLAY INVISIBLE (3250 1450);
FORCEPROP 1 LAST PATH I61
J 0
(2923 1575);
DISPLAY 0.872340 (2923 1575);
PAINT GREEN (2923 1575);
DISPLAY INVISIBLE (2923 1575);
FORCEADD TAP..1
(2925 1625);
FORCEPROP 3 LASTPIN (2875 1625) SIG_NAME UPI_CPU0_CPU1_P1P0_DN<9>
J 0
(2885 1635);
DISPLAY 0.659574 (2885 1635);
PAINT MONO (2885 1635);
DISPLAY INVISIBLE (2885 1635);
FORCEPROP 1 LASTPIN (2875 1625) BN 9
J 0
(2863 1633);
DISPLAY 0.680851 (2863 1633);
PAINT GREEN (2863 1633);
FORCEPROP 2 LAST CDS_LIB standard
J 0
(2925 1625);
PAINT MONO (2925 1625);
DISPLAY INVISIBLE (2925 1625);
FORCEPROP 1 LAST BODY_TYPE PLUMBING
J 0
(2925 1675);
DISPLAY 0.872340 (2925 1675);
PAINT GREEN (2925 1675);
DISPLAY INVISIBLE (2925 1675);
FORCEPROP 1 LAST HDL_TAP TRUE
J 0
(3250 1500);
DISPLAY 0.872340 (3250 1500);
DISPLAY INVISIBLE (3250 1500);
FORCEPROP 1 LAST PATH I62
J 0
(2923 1625);
DISPLAY 0.872340 (2923 1625);
PAINT GREEN (2923 1625);
DISPLAY INVISIBLE (2923 1625);
FORCEADD TAP..1
R 2
(-850 1525);
FORCEPROP 3 LASTPIN (-800 1525) SIG_NAME UPI_CPU1_CPU0_P0P1_DN<7>
J 0
(-790 1535);
DISPLAY 0.659574 (-790 1535);
PAINT MONO (-790 1535);
DISPLAY INVISIBLE (-790 1535);
FORCEPROP 1 LASTPIN (-800 1525) BN 7
J 2
(-788 1533);
DISPLAY 0.680851 (-788 1533);
PAINT GREEN (-788 1533);
FORCEPROP 2 LAST CDS_LIB standard
J 0
(-850 1525);
DISPLAY INVISIBLE (-850 1525);
FORCEPROP 1 LAST BODY_TYPE PLUMBING
J 2
(-850 1575);
DISPLAY 0.872340 (-850 1575);
PAINT GREEN (-850 1575);
DISPLAY INVISIBLE (-850 1575);
FORCEPROP 1 LAST HDL_TAP TRUE
J 2
(-1175 1400);
DISPLAY 0.872340 (-1175 1400);
DISPLAY INVISIBLE (-1175 1400);
FORCEPROP 1 LAST PATH I7
J 2
(-848 1525);
DISPLAY 0.872340 (-848 1525);
PAINT GREEN (-848 1525);
DISPLAY INVISIBLE (-848 1525);
FORCEADD TAP..1
(2725 2425);
FORCEPROP 3 LASTPIN (2675 2425) SIG_NAME UPI_CPU0_CPU1_P1P0_DP<0>
J 0
(2685 2435);
DISPLAY 0.659574 (2685 2435);
PAINT MONO (2685 2435);
DISPLAY INVISIBLE (2685 2435);
FORCEPROP 1 LASTPIN (2675 2425) BN 0
J 0
(2663 2433);
DISPLAY 0.680851 (2663 2433);
PAINT GREEN (2663 2433);
FORCEPROP 2 LAST CDS_LIB standard
J 0
(2725 2425);
PAINT MONO (2725 2425);
DISPLAY INVISIBLE (2725 2425);
FORCEPROP 1 LAST BODY_TYPE PLUMBING
J 0
(2725 2475);
DISPLAY 0.872340 (2725 2475);
PAINT GREEN (2725 2475);
DISPLAY INVISIBLE (2725 2475);
FORCEPROP 1 LAST HDL_TAP TRUE
J 0
(3050 2300);
DISPLAY 0.872340 (3050 2300);
DISPLAY INVISIBLE (3050 2300);
FORCEPROP 1 LAST PATH I75
J 0
(2723 2425);
DISPLAY 0.872340 (2723 2425);
PAINT GREEN (2723 2425);
DISPLAY INVISIBLE (2723 2425);
FORCEADD TAP..1
(2925 2275);
FORCEPROP 3 LASTPIN (2875 2275) SIG_NAME UPI_CPU0_CPU1_P1P0_DN<22>
J 0
(2885 2285);
DISPLAY 0.659574 (2885 2285);
PAINT MONO (2885 2285);
DISPLAY INVISIBLE (2885 2285);
FORCEPROP 1 LASTPIN (2875 2275) BN 22
J 0
(2863 2283);
DISPLAY 0.680851 (2863 2283);
PAINT GREEN (2863 2283);
FORCEPROP 2 LAST CDS_LIB standard
J 0
(2925 2275);
DISPLAY INVISIBLE (2925 2275);
FORCEPROP 1 LAST BODY_TYPE PLUMBING
J 0
(2925 2325);
DISPLAY 0.872340 (2925 2325);
PAINT GREEN (2925 2325);
DISPLAY INVISIBLE (2925 2325);
FORCEPROP 1 LAST HDL_TAP TRUE
J 0
(3250 2150);
DISPLAY 0.872340 (3250 2150);
DISPLAY INVISIBLE (3250 2150);
FORCEPROP 1 LAST PATH I76
J 0
(2923 2275);
DISPLAY 0.872340 (2923 2275);
PAINT GREEN (2923 2275);
DISPLAY INVISIBLE (2923 2275);
FORCEADD TAP..1
(2725 2525);
FORCEPROP 3 LASTPIN (2675 2525) SIG_NAME UPI_CPU0_CPU1_P1P0_DP<2>
J 0
(2685 2535);
DISPLAY 0.659574 (2685 2535);
PAINT MONO (2685 2535);
DISPLAY INVISIBLE (2685 2535);
FORCEPROP 1 LASTPIN (2675 2525) BN 2
J 0
(2663 2533);
DISPLAY 0.680851 (2663 2533);
PAINT GREEN (2663 2533);
FORCEPROP 2 LAST CDS_LIB standard
J 0
(2725 2525);
PAINT MONO (2725 2525);
DISPLAY INVISIBLE (2725 2525);
FORCEPROP 1 LAST BODY_TYPE PLUMBING
J 0
(2725 2575);
DISPLAY 0.872340 (2725 2575);
PAINT GREEN (2725 2575);
DISPLAY INVISIBLE (2725 2575);
FORCEPROP 1 LAST HDL_TAP TRUE
J 0
(3050 2400);
DISPLAY 0.872340 (3050 2400);
DISPLAY INVISIBLE (3050 2400);
FORCEPROP 1 LAST PATH I77
J 0
(2723 2525);
DISPLAY 0.872340 (2723 2525);
PAINT GREEN (2723 2525);
DISPLAY INVISIBLE (2723 2525);
FORCEADD TAP..1
(2725 2475);
FORCEPROP 3 LASTPIN (2675 2475) SIG_NAME UPI_CPU0_CPU1_P1P0_DP<1>
J 0
(2685 2485);
DISPLAY 0.659574 (2685 2485);
PAINT MONO (2685 2485);
DISPLAY INVISIBLE (2685 2485);
FORCEPROP 1 LASTPIN (2675 2475) BN 1
J 0
(2663 2483);
DISPLAY 0.680851 (2663 2483);
PAINT GREEN (2663 2483);
FORCEPROP 2 LAST CDS_LIB standard
J 0
(2725 2475);
PAINT MONO (2725 2475);
DISPLAY INVISIBLE (2725 2475);
FORCEPROP 1 LAST BODY_TYPE PLUMBING
J 0
(2725 2525);
DISPLAY 0.872340 (2725 2525);
PAINT GREEN (2725 2525);
DISPLAY INVISIBLE (2725 2525);
FORCEPROP 1 LAST HDL_TAP TRUE
J 0
(3050 2350);
DISPLAY 0.872340 (3050 2350);
DISPLAY INVISIBLE (3050 2350);
FORCEPROP 1 LAST PATH I78
J 0
(2723 2475);
DISPLAY 0.872340 (2723 2475);
PAINT GREEN (2723 2475);
DISPLAY INVISIBLE (2723 2475);
FORCEADD TAP..1
R 2
(-850 1475);
FORCEPROP 3 LASTPIN (-800 1475) SIG_NAME UPI_CPU1_CPU0_P0P1_DN<6>
J 0
(-790 1485);
DISPLAY 0.659574 (-790 1485);
PAINT MONO (-790 1485);
DISPLAY INVISIBLE (-790 1485);
FORCEPROP 1 LASTPIN (-800 1475) BN 6
J 2
(-788 1483);
DISPLAY 0.680851 (-788 1483);
PAINT GREEN (-788 1483);
FORCEPROP 2 LAST CDS_LIB standard
J 0
(-850 1475);
DISPLAY INVISIBLE (-850 1475);
FORCEPROP 1 LAST BODY_TYPE PLUMBING
J 2
(-850 1525);
DISPLAY 0.872340 (-850 1525);
PAINT GREEN (-850 1525);
DISPLAY INVISIBLE (-850 1525);
FORCEPROP 1 LAST HDL_TAP TRUE
J 2
(-1175 1350);
DISPLAY 0.872340 (-1175 1350);
DISPLAY INVISIBLE (-1175 1350);
FORCEPROP 1 LAST PATH I8
J 2
(-848 1475);
DISPLAY 0.872340 (-848 1475);
PAINT GREEN (-848 1475);
DISPLAY INVISIBLE (-848 1475);
FORCEADD TAP..1
(2725 2625);
FORCEPROP 3 LASTPIN (2675 2625) SIG_NAME UPI_CPU0_CPU1_P1P0_DP<4>
J 0
(2685 2635);
DISPLAY 0.659574 (2685 2635);
PAINT MONO (2685 2635);
DISPLAY INVISIBLE (2685 2635);
FORCEPROP 1 LASTPIN (2675 2625) BN 4
J 0
(2663 2633);
DISPLAY 0.680851 (2663 2633);
PAINT GREEN (2663 2633);
FORCEPROP 2 LAST CDS_LIB standard
J 0
(2725 2625);
PAINT MONO (2725 2625);
DISPLAY INVISIBLE (2725 2625);
FORCEPROP 1 LAST BODY_TYPE PLUMBING
J 0
(2725 2675);
DISPLAY 0.872340 (2725 2675);
PAINT GREEN (2725 2675);
DISPLAY INVISIBLE (2725 2675);
FORCEPROP 1 LAST HDL_TAP TRUE
J 0
(3050 2500);
DISPLAY 0.872340 (3050 2500);
DISPLAY INVISIBLE (3050 2500);
FORCEPROP 1 LAST PATH I81
J 0
(2723 2625);
DISPLAY 0.872340 (2723 2625);
PAINT GREEN (2723 2625);
DISPLAY INVISIBLE (2723 2625);
FORCEADD TAP..1
(2725 2875);
FORCEPROP 3 LASTPIN (2675 2875) SIG_NAME UPI_CPU0_CPU1_P1P0_DP<9>
J 0
(2685 2885);
DISPLAY 0.659574 (2685 2885);
PAINT MONO (2685 2885);
DISPLAY INVISIBLE (2685 2885);
FORCEPROP 1 LASTPIN (2675 2875) BN 9
J 0
(2663 2883);
DISPLAY 0.680851 (2663 2883);
PAINT GREEN (2663 2883);
FORCEPROP 2 LAST CDS_LIB standard
J 0
(2725 2875);
PAINT MONO (2725 2875);
DISPLAY INVISIBLE (2725 2875);
FORCEPROP 1 LAST BODY_TYPE PLUMBING
J 0
(2725 2925);
DISPLAY 0.872340 (2725 2925);
PAINT GREEN (2725 2925);
DISPLAY INVISIBLE (2725 2925);
FORCEPROP 1 LAST HDL_TAP TRUE
J 0
(3050 2750);
DISPLAY 0.872340 (3050 2750);
DISPLAY INVISIBLE (3050 2750);
FORCEPROP 1 LAST PATH I82
J 0
(2723 2875);
DISPLAY 0.872340 (2723 2875);
PAINT GREEN (2723 2875);
DISPLAY INVISIBLE (2723 2875);
FORCEADD TAP..1
(2725 2825);
FORCEPROP 3 LASTPIN (2675 2825) SIG_NAME UPI_CPU0_CPU1_P1P0_DP<8>
J 0
(2685 2835);
DISPLAY 0.659574 (2685 2835);
PAINT MONO (2685 2835);
DISPLAY INVISIBLE (2685 2835);
FORCEPROP 1 LASTPIN (2675 2825) BN 8
J 0
(2663 2833);
DISPLAY 0.680851 (2663 2833);
PAINT GREEN (2663 2833);
FORCEPROP 2 LAST CDS_LIB standard
J 0
(2725 2825);
PAINT MONO (2725 2825);
DISPLAY INVISIBLE (2725 2825);
FORCEPROP 1 LAST BODY_TYPE PLUMBING
J 0
(2725 2875);
DISPLAY 0.872340 (2725 2875);
PAINT GREEN (2725 2875);
DISPLAY INVISIBLE (2725 2875);
FORCEPROP 1 LAST HDL_TAP TRUE
J 0
(3050 2700);
DISPLAY 0.872340 (3050 2700);
DISPLAY INVISIBLE (3050 2700);
FORCEPROP 1 LAST PATH I84
J 0
(2723 2825);
DISPLAY 0.872340 (2723 2825);
PAINT GREEN (2723 2825);
DISPLAY INVISIBLE (2723 2825);
FORCEADD TAP..1
(2725 2775);
FORCEPROP 3 LASTPIN (2675 2775) SIG_NAME UPI_CPU0_CPU1_P1P0_DP<7>
J 0
(2685 2785);
DISPLAY 0.659574 (2685 2785);
PAINT MONO (2685 2785);
DISPLAY INVISIBLE (2685 2785);
FORCEPROP 1 LASTPIN (2675 2775) BN 7
J 0
(2663 2783);
DISPLAY 0.680851 (2663 2783);
PAINT GREEN (2663 2783);
FORCEPROP 2 LAST CDS_LIB standard
J 0
(2725 2775);
PAINT MONO (2725 2775);
DISPLAY INVISIBLE (2725 2775);
FORCEPROP 1 LAST BODY_TYPE PLUMBING
J 0
(2725 2825);
DISPLAY 0.872340 (2725 2825);
PAINT GREEN (2725 2825);
DISPLAY INVISIBLE (2725 2825);
FORCEPROP 1 LAST HDL_TAP TRUE
J 0
(3050 2650);
DISPLAY 0.872340 (3050 2650);
DISPLAY INVISIBLE (3050 2650);
FORCEPROP 1 LAST PATH I85
J 0
(2723 2775);
DISPLAY 0.872340 (2723 2775);
PAINT GREEN (2723 2775);
DISPLAY INVISIBLE (2723 2775);
FORCEADD TAP..1
(2725 2725);
FORCEPROP 3 LASTPIN (2675 2725) SIG_NAME UPI_CPU0_CPU1_P1P0_DP<6>
J 0
(2685 2735);
DISPLAY 0.659574 (2685 2735);
PAINT MONO (2685 2735);
DISPLAY INVISIBLE (2685 2735);
FORCEPROP 1 LASTPIN (2675 2725) BN 6
J 0
(2663 2733);
DISPLAY 0.680851 (2663 2733);
PAINT GREEN (2663 2733);
FORCEPROP 2 LAST CDS_LIB standard
J 0
(2725 2725);
PAINT MONO (2725 2725);
DISPLAY INVISIBLE (2725 2725);
FORCEPROP 1 LAST BODY_TYPE PLUMBING
J 0
(2725 2775);
DISPLAY 0.872340 (2725 2775);
PAINT GREEN (2725 2775);
DISPLAY INVISIBLE (2725 2775);
FORCEPROP 1 LAST HDL_TAP TRUE
J 0
(3050 2600);
DISPLAY 0.872340 (3050 2600);
DISPLAY INVISIBLE (3050 2600);
FORCEPROP 1 LAST PATH I86
J 0
(2723 2725);
DISPLAY 0.872340 (2723 2725);
PAINT GREEN (2723 2725);
DISPLAY INVISIBLE (2723 2725);
FORCEADD TAP..1
R 2
(-850 1575);
FORCEPROP 3 LASTPIN (-800 1575) SIG_NAME UPI_CPU1_CPU0_P0P1_DN<8>
J 0
(-790 1585);
DISPLAY 0.659574 (-790 1585);
PAINT MONO (-790 1585);
DISPLAY INVISIBLE (-790 1585);
FORCEPROP 1 LASTPIN (-800 1575) BN 8
J 2
(-788 1583);
DISPLAY 0.680851 (-788 1583);
PAINT GREEN (-788 1583);
FORCEPROP 2 LAST CDS_LIB standard
J 0
(-850 1575);
DISPLAY INVISIBLE (-850 1575);
FORCEPROP 1 LAST BODY_TYPE PLUMBING
J 2
(-850 1625);
DISPLAY 0.872340 (-850 1625);
PAINT GREEN (-850 1625);
DISPLAY INVISIBLE (-850 1625);
FORCEPROP 1 LAST HDL_TAP TRUE
J 2
(-1175 1450);
DISPLAY 0.872340 (-1175 1450);
DISPLAY INVISIBLE (-1175 1450);
FORCEPROP 1 LAST PATH I9
J 2
(-848 1575);
DISPLAY 0.872340 (-848 1575);
PAINT GREEN (-848 1575);
DISPLAY INVISIBLE (-848 1575);
FORCEADD TAP..1
(2725 3525);
FORCEPROP 3 LASTPIN (2675 3525) SIG_NAME UPI_CPU0_CPU1_P1P0_DP<22>
J 0
(2685 3535);
DISPLAY 0.659574 (2685 3535);
PAINT MONO (2685 3535);
DISPLAY INVISIBLE (2685 3535);
FORCEPROP 1 LASTPIN (2675 3525) BN 22
J 0
(2663 3533);
DISPLAY 0.680851 (2663 3533);
PAINT GREEN (2663 3533);
FORCEPROP 2 LAST CDS_LIB standard
J 0
(2725 3525);
DISPLAY INVISIBLE (2725 3525);
FORCEPROP 1 LAST BODY_TYPE PLUMBING
J 0
(2725 3575);
DISPLAY 0.872340 (2725 3575);
PAINT GREEN (2725 3575);
DISPLAY INVISIBLE (2725 3575);
FORCEPROP 1 LAST HDL_TAP TRUE
J 0
(3050 3400);
DISPLAY 0.872340 (3050 3400);
DISPLAY INVISIBLE (3050 3400);
FORCEPROP 1 LAST PATH I99
J 0
(2723 3525);
DISPLAY 0.872340 (2723 3525);
PAINT GREEN (2723 3525);
DISPLAY INVISIBLE (2723 3525);
FORCEADD DESIGN_NOTE..1
(3975 3125);
FORCEPROP 0 LAST S1 DP/DN SWAP
J 0
(3775 2975);
DISPLAY 1.021277 (3775 2975);
PAINT SKYBLUE (3775 2975);
FORCEPROP 2 LAST CDS_LIB logical_power
J 0
(3975 3125);
DISPLAY INVISIBLE (3975 3125);
FORCEPROP 1 LAST COMMENT_BODY TRUE
J 0
(4000 3225);
DISPLAY 0.978723 (4000 3225);
DISPLAY INVISIBLE (4000 3225);
FORCEADD DESIGN_NOTE..1
(-1850 3125);
FORCEPROP 0 LAST S1 DP/DN SWAP
J 0
(-2050 2975);
DISPLAY 1.021277 (-2050 2975);
PAINT SKYBLUE (-2050 2975);
FORCEPROP 2 LAST CDS_LIB logical_power
J 0
(-1850 3125);
DISPLAY INVISIBLE (-1850 3125);
FORCEPROP 1 LAST COMMENT_BODY TRUE
J 0
(-1825 3225);
DISPLAY 0.978723 (-1825 3225);
DISPLAY INVISIBLE (-1825 3225);
FORCEADD QUANTA_TITLE_BLOCK_C..1
(5650 -1925);
FORCEPROP 0 LAST CDS_CON_LAST_MODIFIED Fri Aug 25 14:00:17 2023
J 0
(3765 -1910);
PAINT MONO (3765 -1910);
DISPLAY INVISIBLE (3765 -1910);
FORCEPROP 1 LAST CUSTOM_TXT_CDS <CON_LAST_MODIFIED>
J 0
(3765 -1910);
DISPLAY 0.978723 (3765 -1910);
FORCEPROP 2 LAST CUSTOM_TXT_CDS <XR_PAGE_TITLE>
J 0
(-2240 3325);
DISPLAY 0.638298 (-2240 3325);
PAINT PINK (-2240 3325);
DISPLAY INVISIBLE (-2240 3325);
FORCEPROP 2 LAST CUSTOM_TXT_CDS <Q_NUMBER>
J 0
(4247 -1822);
DISPLAY 1.212766 (4247 -1822);
FORCEPROP 1 LAST CUSTOM_TXT_CDS <NAME_2>
J 0
(2475 -1875);
FORCEPROP 1 LAST CUSTOM_TXT_CDS <NAME_1>
J 0
(2475 -1750);
FORCEPROP 1 LAST CUSTOM_TXT_CDS <Q_PROJ>
J 0
(3268 -1823);
DISPLAY 1.212766 (3268 -1823);
FORCEPROP 1 LAST CUSTOM_TXT_CDS <Q_REV>
J 0
(5466 -1822);
DISPLAY 1.212766 (5466 -1822);
FORCEPROP 1 LAST CUSTOM_TXT_CDS <CON_PAGE_NUM> OF <CON_TOTAL_PAGES>
J 0
(5204 -1907);
DISPLAY 0.978723 (5204 -1907);
FORCEPROP 1 LAST Q_TITLE SPR CPU0 - UPI1 (21 OF 30)
J 0
(-3716 -1899);
DISPLAY 1.957447 (-3716 -1899);
PAINT GREEN (-3716 -1899);
FORCEPROP 1 LAST Q_DEPT 
J 1
(1887 -1876);
DISPLAY 1.957447 (1887 -1876);
PAINT GREEN (1887 -1876);
FORCEPROP 2 LAST CDS_LIB pure_quanta
J 0
(5650 -1925);
PAINT MONO (5650 -1925);
DISPLAY INVISIBLE (5650 -1925);
FORCEPROP 1 LAST CDS_LMAN_SYM_OUTLINE -9475,6775,100,-125
J 0
(5650 -1925);
DISPLAY 0.468085 (5650 -1925);
PAINT GREEN (5650 -1925);
DISPLAY INVISIBLE (5650 -1925);
FORCEPROP 2 LAST PAGE_BORDER TRUE
J 0
(-2240 3325);
DISPLAY 0.638298 (-2240 3325);
PAINT PINK (-2240 3325);
DISPLAY INVISIBLE (-2240 3325);
FORCEPROP 2 LAST CDS_XR_PAGE_TITLE CR-33 : @S9S_MB_2U_LIB.S9S_MB_2U(SCH_1):PAGE33
J 0
(-2240 3325);
DISPLAY 0.638298 (-2240 3325);
PAINT PINK (-2240 3325);
DISPLAY INVISIBLE (-2240 3325);
FORCEPROP 1 LAST COMMENT_BODY TRUE
J 0
(5662 -1938);
DISPLAY 0.978723 (5662 -1938);
PAINT GREEN (5662 -1938);
DISPLAY INVISIBLE (5662 -1938);
WIRE 17 -1 (2775 2450)(2775 2500);
WIRE 17 -1 (2775 2450)(2775 2350);
WIRE 17 -1 (2775 2500)(2775 2550);
WIRE 17 -1 (2775 2650)(2775 2550);
WIRE 17 -1 (2775 2350)(2775 2250);
WIRE 17 -1 (2775 2250)(2775 2200);
WIRE 17 -1 (2775 2750)(2775 2650);
WIRE 17 -1 (2775 2750)(2775 2800);
WIRE 17 -1 (2775 2200)(2775 2150);
WIRE 17 -1 (2775 2150)(2775 2100);
WIRE 17 -1 (2775 2800)(2775 2850);
WIRE 17 -1 (2775 2850)(2775 2900);
WIRE 17 -1 (2775 2100)(2775 2050);
WIRE 17 -1 (2775 2050)(2775 2000);
WIRE 17 -1 (2775 2900)(2775 3550);
WIRE 17 -1 (2775 3550)(2775 3725);
WIRE 17 -1 (2775 2000)(2775 1950);
WIRE 17 -1 (2775 1950)(2775 1900);
WIRE 17 -1 (2775 3725)(4025 3725);
FORCEPROP 2 LAST SIG_NAME UPI_CPU0_CPU1_P1P0_DP<23:0>
J 0
(2915 3735);
DISPLAY 0.680851 (2915 3735);
PAINT WHITE (2915 3735);
WIRE 17 -1 (2975 2700)(2975 2600);
WIRE 17 -1 (2975 2950)(2975 2700);
WIRE 17 -1 (2975 2600)(2975 2400);
WIRE 17 -1 (2975 2400)(4025 2400);
FORCEPROP 2 LAST SIG_NAME UPI_CPU0_CPU1_P1P0_DN<23:0>
J 0
(3115 2410);
DISPLAY 0.680851 (3115 2410);
PAINT WHITE (3115 2410);
WIRE 17 -1 (2975 3000)(2975 2950);
WIRE 17 -1 (2975 3050)(2975 3000);
WIRE 17 -1 (2975 3100)(2975 3050);
WIRE 17 -1 (2975 3150)(2975 3100);
WIRE 17 -1 (2975 3200)(2975 3150);
WIRE 17 -1 (2975 3250)(2975 3200);
WIRE 17 -1 (2975 3300)(2975 3250);
WIRE 17 -1 (2975 3350)(2975 3300);
WIRE 17 -1 (2975 3400)(2975 3350);
WIRE 17 -1 (2975 3400)(2975 3450);
WIRE 17 -1 (2975 3450)(2975 3500);
WIRE 17 -1 (2975 3500)(2975 3600);
WIRE 17 -1 (2975 1200)(2975 1250);
WIRE 17 -1 (2975 1250)(2975 1300);
WIRE 17 -1 (2975 1400)(2975 1300);
WIRE 17 -1 (2975 1400)(2975 1500);
WIRE 17 -1 (2975 1500)(2975 1550);
WIRE 17 -1 (2975 1550)(2975 1600);
WIRE 17 -1 (2975 1650)(2975 1600);
WIRE 17 -1 (2975 1650)(2975 2300);
WIRE 17 -1 (2975 2300)(2975 2400);
WIRE 17 -1 (2775 1450)(2775 1350);
WIRE 17 -1 (2775 1700)(2775 1450);
WIRE 17 -1 (2775 1750)(2775 1700);
WIRE 17 -1 (2775 1800)(2775 1750);
WIRE 17 -1 (2775 1850)(2775 1800);
WIRE 17 -1 (2775 1900)(2775 1850);
WIRE 17 -1 (-700 2450)(-700 2500);
WIRE 17 -1 (-700 2450)(-700 2350);
WIRE 17 -1 (-700 2600)(-700 2500);
WIRE 17 -1 (-700 2600)(-700 2650);
WIRE 17 -1 (-700 2350)(-700 2300);
WIRE 17 -1 (-700 2300)(-700 2200);
WIRE 17 -1 (-700 2650)(-700 2700);
WIRE 17 -1 (-700 2700)(-700 2750);
WIRE 17 -1 (-700 2200)(-700 2150);
WIRE 17 -1 (-700 2050)(-700 2150);
WIRE 17 -1 (-700 2750)(-700 2800);
WIRE 17 -1 (-700 2800)(-700 2850);
WIRE 17 -1 (-700 2050)(-700 1800);
WIRE 17 -1 (-700 1800)(-700 1300);
WIRE 17 -1 (-700 2850)(-700 2900);
WIRE 17 -1 (-700 2900)(-700 2950);
WIRE 17 -1 (-700 2950)(-700 3000);
WIRE 17 -1 (-700 3100)(-700 3000);
WIRE 17 -1 (-700 3100)(-700 3150);
WIRE 17 -1 (-700 3150)(-700 3200);
WIRE 17 -1 (-700 3200)(-700 3250);
WIRE 17 -1 (-700 3250)(-700 3350);
WIRE 17 -1 (-700 3500)(-700 3350);
WIRE 17 -1 (-700 3500)(-700 3675);
WIRE 17 -1 (-1850 3675)(-700 3675);
FORCEPROP 2 LAST SIG_NAME UPI_CPU1_CPU0_P0P1_DP<23:0>
J 0
(-1735 3685);
DISPLAY 0.680851 (-1735 3685);
PAINT WHITE (-1735 3685);
WIRE 17 -1 (-900 2400)(-900 2550);
WIRE 17 -1 (-900 2250)(-900 2400);
WIRE 17 -1 (-1850 2400)(-900 2400);
FORCEPROP 2 LAST SIG_NAME UPI_CPU1_CPU0_P0P1_DN<23:0>
J 0
(-1835 2410);
DISPLAY 0.680851 (-1835 2410);
PAINT WHITE (-1835 2410);
WIRE 17 -1 (-900 2550)(-900 3050);
WIRE 17 -1 (-900 3050)(-900 3300);
WIRE 17 -1 (-900 3300)(-900 3400);
WIRE 17 -1 (-900 3400)(-900 3450);
WIRE 17 -1 (-900 3450)(-900 3550);
WIRE 17 -1 (-900 3550)(-900 3600);
WIRE 17 -1 (-900 1200)(-900 1250);
WIRE 17 -1 (-900 1350)(-900 1250);
WIRE 17 -1 (-900 1350)(-900 1400);
WIRE 17 -1 (-900 1400)(-900 1450);
WIRE 17 -1 (-900 1450)(-900 1500);
WIRE 17 -1 (-900 1500)(-900 1550);
WIRE 17 -1 (-900 1550)(-900 1600);
WIRE 17 -1 (-900 1600)(-900 1650);
WIRE 17 -1 (-900 1650)(-900 1700);
WIRE 17 -1 (-900 1700)(-900 1750);
WIRE 17 -1 (-900 1750)(-900 1850);
WIRE 17 -1 (-900 1850)(-900 1900);
WIRE 17 -1 (-900 1900)(-900 1950);
WIRE 17 -1 (-900 1950)(-900 2000);
WIRE 17 -1 (-900 2100)(-900 2000);
WIRE 17 -1 (-900 2250)(-900 2100);
WIRE 16 -1 (-600 2325)(-150 2325);
WIRE 16 -1 (-600 2275)(-150 2275);
WIRE 16 -1 (-800 2225)(-150 2225);
WIRE 16 -1 (-600 2175)(-150 2175);
WIRE 16 -1 (-600 2125)(-150 2125);
WIRE 16 -1 (-800 2075)(-150 2075);
WIRE 16 -1 (-600 2025)(-150 2025);
WIRE 16 -1 (-800 1975)(-150 1975);
WIRE 16 -1 (-800 1925)(-150 1925);
WIRE 16 -1 (-800 1875)(-150 1875);
WIRE 16 -1 (-800 1825)(-150 1825);
WIRE 16 -1 (-600 1775)(-150 1775);
WIRE 16 -1 (-800 1725)(-150 1725);
WIRE 16 -1 (-800 1675)(-150 1675);
WIRE 16 -1 (-800 1625)(-150 1625);
WIRE 16 -1 (-800 1575)(-150 1575);
WIRE 16 -1 (-800 1525)(-150 1525);
WIRE 16 -1 (-800 1475)(-150 1475);
WIRE 16 -1 (-800 1425)(-150 1425);
WIRE 16 -1 (-800 1375)(-150 1375);
WIRE 16 -1 (-800 1325)(-150 1325);
WIRE 16 -1 (-600 1275)(-150 1275);
WIRE 16 -1 (-800 1225)(-150 1225);
WIRE 16 -1 (-800 1175)(-150 1175);
WIRE 16 -1 (-150 3575)(-800 3575);
WIRE 16 -1 (-150 3525)(-800 3525);
WIRE 16 -1 (-600 3475)(-150 3475);
WIRE 16 -1 (-150 3425)(-800 3425);
WIRE 16 -1 (-150 3375)(-800 3375);
WIRE 16 -1 (-600 3325)(-150 3325);
WIRE 16 -1 (-800 3275)(-150 3275);
WIRE 16 -1 (-600 3225)(-150 3225);
WIRE 16 -1 (-600 3175)(-150 3175);
WIRE 16 -1 (-600 3125)(-150 3125);
WIRE 16 -1 (-600 3075)(-150 3075);
WIRE 16 -1 (-800 3025)(-150 3025);
WIRE 16 -1 (-600 2975)(-150 2975);
WIRE 16 -1 (-600 2925)(-150 2925);
WIRE 16 -1 (-600 2875)(-150 2875);
WIRE 16 -1 (-600 2825)(-150 2825);
WIRE 16 -1 (-600 2775)(-150 2775);
WIRE 16 -1 (-600 2725)(-150 2725);
WIRE 16 -1 (-600 2675)(-150 2675);
WIRE 16 -1 (-600 2625)(-150 2625);
WIRE 16 -1 (-600 2575)(-150 2575);
WIRE 16 -1 (-800 2525)(-150 2525);
WIRE 16 -1 (-600 2475)(-150 2475);
WIRE 16 -1 (-600 2425)(-150 2425);
WIRE 16 -1 (2250 2325)(2675 2325);
WIRE 16 -1 (2250 2275)(2875 2275);
WIRE 16 -1 (2250 2225)(2675 2225);
WIRE 16 -1 (2250 2175)(2675 2175);
WIRE 16 -1 (2250 2125)(2675 2125);
WIRE 16 -1 (2250 2075)(2675 2075);
WIRE 16 -1 (2250 2025)(2675 2025);
WIRE 16 -1 (2250 1975)(2675 1975);
WIRE 16 -1 (2250 1925)(2675 1925);
WIRE 16 -1 (2250 1875)(2675 1875);
WIRE 16 -1 (2250 1825)(2675 1825);
WIRE 16 -1 (2250 1775)(2675 1775);
WIRE 16 -1 (2250 1725)(2675 1725);
WIRE 16 -1 (2250 1675)(2675 1675);
WIRE 16 -1 (2250 1625)(2875 1625);
WIRE 16 -1 (2250 1575)(2875 1575);
WIRE 16 -1 (2250 1525)(2875 1525);
WIRE 16 -1 (2250 1475)(2875 1475);
WIRE 16 -1 (2250 1425)(2675 1425);
WIRE 16 -1 (2250 1375)(2875 1375);
WIRE 16 -1 (2250 1325)(2675 1325);
WIRE 16 -1 (2250 1275)(2875 1275);
WIRE 16 -1 (2250 1225)(2875 1225);
WIRE 16 -1 (2250 1175)(2875 1175);
WIRE 16 -1 (2250 3575)(2875 3575);
WIRE 16 -1 (2250 3525)(2675 3525);
WIRE 16 -1 (2250 3475)(2875 3475);
WIRE 16 -1 (2250 3425)(2875 3425);
WIRE 16 -1 (2250 3375)(2875 3375);
WIRE 16 -1 (2250 3325)(2875 3325);
FORCEPROP 0 LAST $PNN UPI_CPU0_CPU1_P1P0_DN<18>
J 0
(2775 3325);
DISPLAY INVISIBLE (2775 3325);
WIRE 16 -1 (2250 3275)(2875 3275);
WIRE 16 -1 (2250 3225)(2875 3225);
WIRE 16 -1 (2250 3175)(2875 3175);
WIRE 16 -1 (2250 3125)(2875 3125);
FORCEPROP 0 LAST $PNN UPI_CPU0_CPU1_P1P0_DN<14>
J 0
(2775 3125);
DISPLAY INVISIBLE (2775 3125);
WIRE 16 -1 (2250 3075)(2875 3075);
WIRE 16 -1 (2250 3025)(2875 3025);
WIRE 16 -1 (2250 2975)(2875 2975);
WIRE 16 -1 (2250 2925)(2875 2925);
WIRE 16 -1 (2250 2875)(2675 2875);
WIRE 16 -1 (2250 2825)(2675 2825);
WIRE 16 -1 (2250 2775)(2675 2775);
WIRE 16 -1 (2250 2725)(2675 2725);
WIRE 16 -1 (2250 2675)(2875 2675);
WIRE 16 -1 (2250 2625)(2675 2625);
WIRE 16 -1 (2250 2575)(2875 2575);
WIRE 16 -1 (2250 2525)(2675 2525);
WIRE 16 -1 (2250 2475)(2675 2475);
WIRE 16 -1 (2250 2425)(2675 2425);
DOT 1 (-900 2400);
DOT 1 (2975 2400);
QUIT
